(kicad_sch
	(version 20250114)
	(generator "eeschema")
	(generator_version "9.0")
	(paper "A3")
	(title_block
		(title "Kintex 410T devboard")
		(date "2024-04-03")
		(rev "1.1.2")
	)
	(junction
		(at 134.62 44.45)
		(diameter 0)
		(color 0 0 0 0)
	)
	(junction
		(at 157.48 44.45)
		(diameter 0)
		(color 0 0 0 0)
	)
	(junction
		(at 255.27 54.61)
		(diameter 0)
		(color 0 0 0 0)
	)
	(junction
		(at 270.51 54.61)
		(diameter 0)
		(color 0 0 0 0)
	)
	(junction
		(at 149.86 44.45)
		(diameter 0)
		(color 0 0 0 0)
	)
	(junction
		(at 255.27 44.45)
		(diameter 0)
		(color 0 0 0 0)
	)
	(junction
		(at 285.75 44.45)
		(diameter 0)
		(color 0 0 0 0)
	)
	(junction
		(at 270.51 109.22)
		(diameter 0)
		(color 0 0 0 0)
	)
	(junction
		(at 293.37 44.45)
		(diameter 0)
		(color 0 0 0 0)
	)
	(junction
		(at 293.37 54.61)
		(diameter 0)
		(color 0 0 0 0)
	)
	(junction
		(at 278.13 54.61)
		(diameter 0)
		(color 0 0 0 0)
	)
	(junction
		(at 300.99 54.61)
		(diameter 0)
		(color 0 0 0 0)
	)
	(junction
		(at 172.72 54.61)
		(diameter 0)
		(color 0 0 0 0)
	)
	(junction
		(at 165.1 54.61)
		(diameter 0)
		(color 0 0 0 0)
	)
	(junction
		(at 300.99 44.45)
		(diameter 0)
		(color 0 0 0 0)
	)
	(junction
		(at 247.65 44.45)
		(diameter 0)
		(color 0 0 0 0)
	)
	(junction
		(at 172.72 44.45)
		(diameter 0)
		(color 0 0 0 0)
	)
	(junction
		(at 261.62 147.32)
		(diameter 0)
		(color 0 0 0 0)
	)
	(junction
		(at 278.13 44.45)
		(diameter 0)
		(color 0 0 0 0)
	)
	(junction
		(at 270.51 44.45)
		(diameter 0)
		(color 0 0 0 0)
	)
	(junction
		(at 270.51 175.26)
		(diameter 0)
		(color 0 0 0 0)
	)
	(junction
		(at 262.89 54.61)
		(diameter 0)
		(color 0 0 0 0)
	)
	(junction
		(at 285.75 54.61)
		(diameter 0)
		(color 0 0 0 0)
	)
	(junction
		(at 149.86 54.61)
		(diameter 0)
		(color 0 0 0 0)
	)
	(junction
		(at 165.1 44.45)
		(diameter 0)
		(color 0 0 0 0)
	)
	(junction
		(at 134.62 54.61)
		(diameter 0)
		(color 0 0 0 0)
	)
	(junction
		(at 262.89 44.45)
		(diameter 0)
		(color 0 0 0 0)
	)
	(junction
		(at 142.24 44.45)
		(diameter 0)
		(color 0 0 0 0)
	)
	(junction
		(at 180.34 44.45)
		(diameter 0)
		(color 0 0 0 0)
	)
	(junction
		(at 157.48 54.61)
		(diameter 0)
		(color 0 0 0 0)
	)
	(junction
		(at 142.24 54.61)
		(diameter 0)
		(color 0 0 0 0)
	)
	(no_connect
		(at 242.57 170.18)
	)
	(no_connect
		(at 242.57 147.32)
	)
	(no_connect
		(at 242.57 162.56)
	)
	(no_connect
		(at 242.57 165.1)
	)
	(no_connect
		(at 242.57 149.86)
	)
	(no_connect
		(at 242.57 144.78)
	)
	(no_connect
		(at 187.96 203.2)
	)
	(no_connect
		(at 187.96 195.58)
	)
	(no_connect
		(at 187.96 193.04)
	)
	(no_connect
		(at 187.96 185.42)
	)
	(no_connect
		(at 187.96 182.88)
	)
	(no_connect
		(at 187.96 170.18)
	)
	(no_connect
		(at 187.96 167.64)
	)
	(no_connect
		(at 187.96 165.1)
	)
	(no_connect
		(at 187.96 83.82)
	)
	(no_connect
		(at 187.96 119.38)
	)
	(no_connect
		(at 187.96 116.84)
	)
	(no_connect
		(at 187.96 121.92)
	)
	(no_connect
		(at 187.96 162.56)
	)
	(no_connect
		(at 187.96 160.02)
	)
	(no_connect
		(at 187.96 157.48)
	)
	(no_connect
		(at 187.96 154.94)
	)
	(no_connect
		(at 187.96 152.4)
	)
	(no_connect
		(at 187.96 149.86)
	)
	(no_connect
		(at 187.96 147.32)
	)
	(no_connect
		(at 187.96 144.78)
	)
	(no_connect
		(at 187.96 142.24)
	)
	(no_connect
		(at 187.96 132.08)
	)
	(no_connect
		(at 242.57 167.64)
	)
	(bus_entry
		(at 144.78 176.53)
		(size 1.27 1.27)
		(stroke
			(width 0)
			(type default)
		)
	)
	(bus_entry
		(at 261.62 186.69)
		(size -1.27 -1.27)
		(stroke
			(width 0)
			(type default)
		)
	)
	(bus_entry
		(at 261.62 199.39)
		(size -1.27 -1.27)
		(stroke
			(width 0)
			(type default)
		)
	)
	(bus_entry
		(at 261.62 179.07)
		(size -1.27 -1.27)
		(stroke
			(width 0)
			(type default)
		)
	)
	(bus_entry
		(at 163.83 80.01)
		(size 1.27 1.27)
		(stroke
			(width 0)
			(type default)
		)
	)
	(bus_entry
		(at 144.78 128.27)
		(size 1.27 1.27)
		(stroke
			(width 0)
			(type default)
		)
	)
	(bus_entry
		(at 261.62 120.65)
		(size -1.27 -1.27)
		(stroke
			(width 0)
			(type default)
		)
	)
	(bus_entry
		(at 163.83 92.71)
		(size 1.27 1.27)
		(stroke
			(width 0)
			(type default)
		)
	)
	(bus_entry
		(at 261.62 102.87)
		(size -1.27 1.27)
		(stroke
			(width 0)
			(type default)
		)
	)
	(bus_entry
		(at 261.62 123.19)
		(size -1.27 -1.27)
		(stroke
			(width 0)
			(type default)
		)
	)
	(bus_entry
		(at 163.83 102.87)
		(size 1.27 1.27)
		(stroke
			(width 0)
			(type default)
		)
	)
	(bus_entry
		(at 163.83 199.39)
		(size 1.27 -1.27)
		(stroke
			(width 0)
			(type default)
		)
	)
	(bus_entry
		(at 261.62 113.03)
		(size -1.27 -1.27)
		(stroke
			(width 0)
			(type default)
		)
	)
	(bus_entry
		(at 261.62 158.75)
		(size -1.27 1.27)
		(stroke
			(width 0)
			(type default)
		)
	)
	(bus_entry
		(at 163.83 90.17)
		(size 1.27 1.27)
		(stroke
			(width 0)
			(type default)
		)
	)
	(bus_entry
		(at 261.62 171.45)
		(size -1.27 1.27)
		(stroke
			(width 0)
			(type default)
		)
	)
	(bus_entry
		(at 144.78 123.19)
		(size 1.27 1.27)
		(stroke
			(width 0)
			(type default)
		)
	)
	(bus_entry
		(at 163.83 107.95)
		(size 1.27 1.27)
		(stroke
			(width 0)
			(type default)
		)
	)
	(bus_entry
		(at 163.83 95.25)
		(size 1.27 1.27)
		(stroke
			(width 0)
			(type default)
		)
	)
	(bus_entry
		(at 261.62 156.21)
		(size -1.27 1.27)
		(stroke
			(width 0)
			(type default)
		)
	)
	(bus_entry
		(at 163.83 85.09)
		(size 1.27 1.27)
		(stroke
			(width 0)
			(type default)
		)
	)
	(bus_entry
		(at 261.62 90.17)
		(size -1.27 1.27)
		(stroke
			(width 0)
			(type default)
		)
	)
	(bus_entry
		(at 144.78 171.45)
		(size 1.27 1.27)
		(stroke
			(width 0)
			(type default)
		)
	)
	(bus_entry
		(at 146.05 111.76)
		(size -1.27 -1.27)
		(stroke
			(width 0)
			(type default)
		)
	)
	(bus_entry
		(at 261.62 138.43)
		(size -1.27 -1.27)
		(stroke
			(width 0)
			(type default)
		)
	)
	(bus_entry
		(at 163.83 77.47)
		(size 1.27 1.27)
		(stroke
			(width 0)
			(type default)
		)
	)
	(bus_entry
		(at 261.62 133.35)
		(size -1.27 -1.27)
		(stroke
			(width 0)
			(type default)
		)
	)
	(bus_entry
		(at 163.83 105.41)
		(size 1.27 1.27)
		(stroke
			(width 0)
			(type default)
		)
	)
	(bus_entry
		(at 163.83 201.93)
		(size 1.27 -1.27)
		(stroke
			(width 0)
			(type default)
		)
	)
	(bus_entry
		(at 163.83 176.53)
		(size 1.27 -1.27)
		(stroke
			(width 0)
			(type default)
		)
	)
	(bus_entry
		(at 261.62 130.81)
		(size -1.27 -1.27)
		(stroke
			(width 0)
			(type default)
		)
	)
	(bus_entry
		(at 261.62 125.73)
		(size -1.27 -1.27)
		(stroke
			(width 0)
			(type default)
		)
	)
	(bus_entry
		(at 163.83 97.79)
		(size 1.27 1.27)
		(stroke
			(width 0)
			(type default)
		)
	)
	(bus_entry
		(at 261.62 105.41)
		(size -1.27 1.27)
		(stroke
			(width 0)
			(type default)
		)
	)
	(bus_entry
		(at 261.62 196.85)
		(size -1.27 -1.27)
		(stroke
			(width 0)
			(type default)
		)
	)
	(bus_entry
		(at 163.83 100.33)
		(size 1.27 1.27)
		(stroke
			(width 0)
			(type default)
		)
	)
	(bus_entry
		(at 261.62 118.11)
		(size -1.27 -1.27)
		(stroke
			(width 0)
			(type default)
		)
	)
	(bus_entry
		(at 261.62 201.93)
		(size -1.27 -1.27)
		(stroke
			(width 0)
			(type default)
		)
	)
	(bus_entry
		(at 261.62 85.09)
		(size -1.27 1.27)
		(stroke
			(width 0)
			(type default)
		)
	)
	(bus_entry
		(at 261.62 194.31)
		(size -1.27 -1.27)
		(stroke
			(width 0)
			(type default)
		)
	)
	(bus_entry
		(at 261.62 97.79)
		(size -1.27 1.27)
		(stroke
			(width 0)
			(type default)
		)
	)
	(bus_entry
		(at 261.62 151.13)
		(size -1.27 1.27)
		(stroke
			(width 0)
			(type default)
		)
	)
	(bus_entry
		(at 261.62 135.89)
		(size -1.27 -1.27)
		(stroke
			(width 0)
			(type default)
		)
	)
	(bus_entry
		(at 163.83 87.63)
		(size 1.27 1.27)
		(stroke
			(width 0)
			(type default)
		)
	)
	(bus_entry
		(at 261.62 82.55)
		(size -1.27 1.27)
		(stroke
			(width 0)
			(type default)
		)
	)
	(bus_entry
		(at 146.05 114.3)
		(size -1.27 -1.27)
		(stroke
			(width 0)
			(type default)
		)
	)
	(bus_entry
		(at 163.83 191.77)
		(size 1.27 -1.27)
		(stroke
			(width 0)
			(type default)
		)
	)
	(bus_entry
		(at 261.62 143.51)
		(size -1.27 -1.27)
		(stroke
			(width 0)
			(type default)
		)
	)
	(bus_entry
		(at 261.62 80.01)
		(size -1.27 1.27)
		(stroke
			(width 0)
			(type default)
		)
	)
	(bus_entry
		(at 163.83 139.7)
		(size 2.54 -2.54)
		(stroke
			(width 0)
			(type default)
		)
	)
	(bus_entry
		(at 261.62 184.15)
		(size -1.27 -1.27)
		(stroke
			(width 0)
			(type default)
		)
	)
	(bus_entry
		(at 261.62 153.67)
		(size -1.27 1.27)
		(stroke
			(width 0)
			(type default)
		)
	)
	(bus_entry
		(at 261.62 87.63)
		(size -1.27 1.27)
		(stroke
			(width 0)
			(type default)
		)
	)
	(bus_entry
		(at 261.62 100.33)
		(size -1.27 1.27)
		(stroke
			(width 0)
			(type default)
		)
	)
	(bus_entry
		(at 163.83 181.61)
		(size 1.27 -1.27)
		(stroke
			(width 0)
			(type default)
		)
	)
	(bus_entry
		(at 144.78 133.35)
		(size 1.27 1.27)
		(stroke
			(width 0)
			(type default)
		)
	)
	(bus_entry
		(at 163.83 189.23)
		(size 1.27 -1.27)
		(stroke
			(width 0)
			(type default)
		)
	)
	(bus_entry
		(at 261.62 191.77)
		(size -1.27 -1.27)
		(stroke
			(width 0)
			(type default)
		)
	)
	(bus_entry
		(at 163.83 142.24)
		(size 2.54 -2.54)
		(stroke
			(width 0)
			(type default)
		)
	)
	(bus_entry
		(at 261.62 115.57)
		(size -1.27 -1.27)
		(stroke
			(width 0)
			(type default)
		)
	)
	(bus_entry
		(at 261.62 128.27)
		(size -1.27 -1.27)
		(stroke
			(width 0)
			(type default)
		)
	)
	(bus_entry
		(at 261.62 181.61)
		(size -1.27 -1.27)
		(stroke
			(width 0)
			(type default)
		)
	)
	(bus_entry
		(at 261.62 95.25)
		(size -1.27 1.27)
		(stroke
			(width 0)
			(type default)
		)
	)
	(bus_entry
		(at 261.62 92.71)
		(size -1.27 1.27)
		(stroke
			(width 0)
			(type default)
		)
	)
	(bus_entry
		(at 261.62 189.23)
		(size -1.27 -1.27)
		(stroke
			(width 0)
			(type default)
		)
	)
	(bus_entry
		(at 261.62 140.97)
		(size -1.27 -1.27)
		(stroke
			(width 0)
			(type default)
		)
	)
	(bus
		(pts
			(xy 162.56 144.78) (xy 163.83 143.51)
		)
		(stroke
			(width 0)
			(type default)
		)
	)
	(wire
		(pts
			(xy 146.05 124.46) (xy 187.96 124.46)
		)
		(stroke
			(width 0)
			(type default)
		)
	)
	(bus
		(pts
			(xy 261.62 118.11) (xy 261.62 120.65)
		)
		(stroke
			(width 0)
			(type default)
		)
	)
	(wire
		(pts
			(xy 134.62 44.45) (xy 129.54 44.45)
		)
		(stroke
			(width 0)
			(type default)
		)
	)
	(wire
		(pts
			(xy 270.51 116.84) (xy 270.51 118.11)
		)
		(stroke
			(width 0)
			(type default)
		)
	)
	(wire
		(pts
			(xy 260.35 81.28) (xy 242.57 81.28)
		)
		(stroke
			(width 0)
			(type default)
		)
	)
	(wire
		(pts
			(xy 134.62 44.45) (xy 142.24 44.45)
		)
		(stroke
			(width 0)
			(type default)
		)
	)
	(bus
		(pts
			(xy 163.83 100.33) (xy 163.83 102.87)
		)
		(stroke
			(width 0)
			(type default)
		)
	)
	(bus
		(pts
			(xy 163.83 102.87) (xy 163.83 105.41)
		)
		(stroke
			(width 0)
			(type default)
		)
	)
	(bus
		(pts
			(xy 163.83 97.79) (xy 163.83 100.33)
		)
		(stroke
			(width 0)
			(type default)
		)
	)
	(wire
		(pts
			(xy 185.42 44.45) (xy 185.42 74.93)
		)
		(stroke
			(width 0)
			(type default)
		)
	)
	(wire
		(pts
			(xy 142.24 54.61) (xy 142.24 52.07)
		)
		(stroke
			(width 0)
			(type default)
		)
	)
	(wire
		(pts
			(xy 243.84 44.45) (xy 243.84 74.93)
		)
		(stroke
			(width 0)
			(type default)
		)
	)
	(wire
		(pts
			(xy 165.1 200.66) (xy 187.96 200.66)
		)
		(stroke
			(width 0)
			(type default)
		)
	)
	(bus
		(pts
			(xy 261.62 100.33) (xy 261.62 102.87)
		)
		(stroke
			(width 0)
			(type default)
		)
	)
	(wire
		(pts
			(xy 260.35 132.08) (xy 242.57 132.08)
		)
		(stroke
			(width 0)
			(type default)
		)
	)
	(wire
		(pts
			(xy 247.65 44.45) (xy 243.84 44.45)
		)
		(stroke
			(width 0)
			(type default)
		)
	)
	(wire
		(pts
			(xy 146.05 111.76) (xy 187.96 111.76)
		)
		(stroke
			(width 0)
			(type default)
		)
	)
	(wire
		(pts
			(xy 260.35 114.3) (xy 242.57 114.3)
		)
		(stroke
			(width 0)
			(type default)
		)
	)
	(bus
		(pts
			(xy 261.62 186.69) (xy 261.62 189.23)
		)
		(stroke
			(width 0)
			(type default)
		)
	)
	(wire
		(pts
			(xy 242.57 193.04) (xy 260.35 193.04)
		)
		(stroke
			(width 0)
			(type default)
		)
	)
	(wire
		(pts
			(xy 129.54 41.91) (xy 129.54 44.45)
		)
		(stroke
			(width 0)
			(type default)
		)
	)
	(bus
		(pts
			(xy 261.62 194.31) (xy 261.62 196.85)
		)
		(stroke
			(width 0)
			(type default)
		)
	)
	(wire
		(pts
			(xy 242.57 172.72) (xy 260.35 172.72)
		)
		(stroke
			(width 0)
			(type default)
		)
	)
	(wire
		(pts
			(xy 134.62 54.61) (xy 134.62 52.07)
		)
		(stroke
			(width 0)
			(type default)
		)
	)
	(wire
		(pts
			(xy 165.1 109.22) (xy 187.96 109.22)
		)
		(stroke
			(width 0)
			(type default)
		)
	)
	(wire
		(pts
			(xy 260.35 93.98) (xy 242.57 93.98)
		)
		(stroke
			(width 0)
			(type default)
		)
	)
	(bus
		(pts
			(xy 144.78 110.49) (xy 144.78 113.03)
		)
		(stroke
			(width 0)
			(type default)
		)
	)
	(bus
		(pts
			(xy 163.83 199.39) (xy 163.83 201.93)
		)
		(stroke
			(width 0)
			(type default)
		)
	)
	(wire
		(pts
			(xy 165.1 88.9) (xy 187.96 88.9)
		)
		(stroke
			(width 0)
			(type default)
		)
	)
	(wire
		(pts
			(xy 242.57 137.16) (xy 260.35 137.16)
		)
		(stroke
			(width 0)
			(type default)
		)
	)
	(bus
		(pts
			(xy 163.83 201.93) (xy 163.83 205.74)
		)
		(stroke
			(width 0)
			(type default)
		)
	)
	(wire
		(pts
			(xy 270.51 107.95) (xy 270.51 109.22)
		)
		(stroke
			(width 0)
			(type default)
		)
	)
	(wire
		(pts
			(xy 260.35 157.48) (xy 242.57 157.48)
		)
		(stroke
			(width 0)
			(type default)
		)
	)
	(wire
		(pts
			(xy 165.1 190.5) (xy 187.96 190.5)
		)
		(stroke
			(width 0)
			(type default)
		)
	)
	(wire
		(pts
			(xy 146.05 172.72) (xy 187.96 172.72)
		)
		(stroke
			(width 0)
			(type default)
		)
	)
	(bus
		(pts
			(xy 261.62 97.79) (xy 261.62 100.33)
		)
		(stroke
			(width 0)
			(type default)
		)
	)
	(wire
		(pts
			(xy 165.1 93.98) (xy 187.96 93.98)
		)
		(stroke
			(width 0)
			(type default)
		)
	)
	(wire
		(pts
			(xy 255.27 54.61) (xy 262.89 54.61)
		)
		(stroke
			(width 0)
			(type default)
		)
	)
	(wire
		(pts
			(xy 270.51 46.99) (xy 270.51 44.45)
		)
		(stroke
			(width 0)
			(type default)
		)
	)
	(bus
		(pts
			(xy 163.83 143.51) (xy 163.83 142.24)
		)
		(stroke
			(width 0)
			(type default)
		)
	)
	(wire
		(pts
			(xy 165.1 175.26) (xy 187.96 175.26)
		)
		(stroke
			(width 0)
			(type default)
		)
	)
	(bus
		(pts
			(xy 261.62 76.2) (xy 261.62 80.01)
		)
		(stroke
			(width 0)
			(type default)
		)
	)
	(wire
		(pts
			(xy 247.65 62.23) (xy 255.27 62.23)
		)
		(stroke
			(width 0)
			(type default)
		)
	)
	(wire
		(pts
			(xy 255.27 54.61) (xy 247.65 54.61)
		)
		(stroke
			(width 0)
			(type default)
		)
	)
	(bus
		(pts
			(xy 163.83 95.25) (xy 163.83 97.79)
		)
		(stroke
			(width 0)
			(type default)
		)
	)
	(wire
		(pts
			(xy 180.34 54.61) (xy 172.72 54.61)
		)
		(stroke
			(width 0)
			(type default)
		)
	)
	(wire
		(pts
			(xy 300.99 54.61) (xy 300.99 55.88)
		)
		(stroke
			(width 0)
			(type default)
		)
	)
	(bus
		(pts
			(xy 163.83 80.01) (xy 163.83 85.09)
		)
		(stroke
			(width 0)
			(type default)
		)
	)
	(bus
		(pts
			(xy 144.78 123.19) (xy 144.78 128.27)
		)
		(stroke
			(width 0)
			(type default)
		)
	)
	(wire
		(pts
			(xy 165.1 96.52) (xy 187.96 96.52)
		)
		(stroke
			(width 0)
			(type default)
		)
	)
	(bus
		(pts
			(xy 261.62 147.32) (xy 261.62 151.13)
		)
		(stroke
			(width 0)
			(type default)
		)
	)
	(wire
		(pts
			(xy 142.24 44.45) (xy 142.24 46.99)
		)
		(stroke
			(width 0)
			(type default)
		)
	)
	(wire
		(pts
			(xy 300.99 44.45) (xy 293.37 44.45)
		)
		(stroke
			(width 0)
			(type default)
		)
	)
	(wire
		(pts
			(xy 242.57 152.4) (xy 260.35 152.4)
		)
		(stroke
			(width 0)
			(type default)
		)
	)
	(bus
		(pts
			(xy 261.62 95.25) (xy 261.62 97.79)
		)
		(stroke
			(width 0)
			(type default)
		)
	)
	(wire
		(pts
			(xy 242.57 182.88) (xy 260.35 182.88)
		)
		(stroke
			(width 0)
			(type default)
		)
	)
	(wire
		(pts
			(xy 134.62 46.99) (xy 134.62 44.45)
		)
		(stroke
			(width 0)
			(type default)
		)
	)
	(bus
		(pts
			(xy 144.78 109.22) (xy 144.78 110.49)
		)
		(stroke
			(width 0)
			(type default)
		)
	)
	(wire
		(pts
			(xy 165.1 104.14) (xy 187.96 104.14)
		)
		(stroke
			(width 0)
			(type default)
		)
	)
	(wire
		(pts
			(xy 270.51 182.88) (xy 270.51 184.15)
		)
		(stroke
			(width 0)
			(type default)
		)
	)
	(wire
		(pts
			(xy 260.35 160.02) (xy 242.57 160.02)
		)
		(stroke
			(width 0)
			(type default)
		)
	)
	(bus
		(pts
			(xy 144.78 128.27) (xy 144.78 133.35)
		)
		(stroke
			(width 0)
			(type default)
		)
	)
	(wire
		(pts
			(xy 165.1 101.6) (xy 187.96 101.6)
		)
		(stroke
			(width 0)
			(type default)
		)
	)
	(wire
		(pts
			(xy 293.37 46.99) (xy 293.37 44.45)
		)
		(stroke
			(width 0)
			(type default)
		)
	)
	(wire
		(pts
			(xy 270.51 109.22) (xy 270.51 111.76)
		)
		(stroke
			(width 0)
			(type default)
		)
	)
	(wire
		(pts
			(xy 278.13 44.45) (xy 270.51 44.45)
		)
		(stroke
			(width 0)
			(type default)
		)
	)
	(wire
		(pts
			(xy 293.37 54.61) (xy 300.99 54.61)
		)
		(stroke
			(width 0)
			(type default)
		)
	)
	(wire
		(pts
			(xy 157.48 44.45) (xy 165.1 44.45)
		)
		(stroke
			(width 0)
			(type default)
		)
	)
	(wire
		(pts
			(xy 146.05 129.54) (xy 187.96 129.54)
		)
		(stroke
			(width 0)
			(type default)
		)
	)
	(wire
		(pts
			(xy 172.72 52.07) (xy 172.72 54.61)
		)
		(stroke
			(width 0)
			(type default)
		)
	)
	(bus
		(pts
			(xy 261.62 82.55) (xy 261.62 85.09)
		)
		(stroke
			(width 0)
			(type default)
		)
	)
	(wire
		(pts
			(xy 260.35 104.14) (xy 242.57 104.14)
		)
		(stroke
			(width 0)
			(type default)
		)
	)
	(bus
		(pts
			(xy 163.83 105.41) (xy 163.83 107.95)
		)
		(stroke
			(width 0)
			(type default)
		)
	)
	(wire
		(pts
			(xy 187.96 127) (xy 185.42 127)
		)
		(stroke
			(width 0)
			(type default)
		)
	)
	(wire
		(pts
			(xy 146.05 114.3) (xy 187.96 114.3)
		)
		(stroke
			(width 0)
			(type default)
		)
	)
	(wire
		(pts
			(xy 260.35 91.44) (xy 242.57 91.44)
		)
		(stroke
			(width 0)
			(type default)
		)
	)
	(bus
		(pts
			(xy 261.62 115.57) (xy 261.62 118.11)
		)
		(stroke
			(width 0)
			(type default)
		)
	)
	(bus
		(pts
			(xy 261.62 76.2) (xy 262.89 74.93)
		)
		(stroke
			(width 0)
			(type default)
		)
	)
	(wire
		(pts
			(xy 255.27 44.45) (xy 255.27 46.99)
		)
		(stroke
			(width 0)
			(type default)
		)
	)
	(wire
		(pts
			(xy 242.57 185.42) (xy 260.35 185.42)
		)
		(stroke
			(width 0)
			(type default)
		)
	)
	(wire
		(pts
			(xy 157.48 54.61) (xy 157.48 52.07)
		)
		(stroke
			(width 0)
			(type default)
		)
	)
	(wire
		(pts
			(xy 260.35 142.24) (xy 242.57 142.24)
		)
		(stroke
			(width 0)
			(type default)
		)
	)
	(wire
		(pts
			(xy 165.1 81.28) (xy 187.96 81.28)
		)
		(stroke
			(width 0)
			(type default)
		)
	)
	(wire
		(pts
			(xy 165.1 187.96) (xy 187.96 187.96)
		)
		(stroke
			(width 0)
			(type default)
		)
	)
	(wire
		(pts
			(xy 260.35 127) (xy 242.57 127)
		)
		(stroke
			(width 0)
			(type default)
		)
	)
	(wire
		(pts
			(xy 172.72 44.45) (xy 180.34 44.45)
		)
		(stroke
			(width 0)
			(type default)
		)
	)
	(bus
		(pts
			(xy 261.62 123.19) (xy 261.62 125.73)
		)
		(stroke
			(width 0)
			(type default)
		)
	)
	(bus
		(pts
			(xy 261.62 90.17) (xy 261.62 92.71)
		)
		(stroke
			(width 0)
			(type default)
		)
	)
	(bus
		(pts
			(xy 163.83 205.74) (xy 162.56 207.01)
		)
		(stroke
			(width 0)
			(type default)
		)
	)
	(wire
		(pts
			(xy 242.57 109.22) (xy 270.51 109.22)
		)
		(stroke
			(width 0)
			(type default)
		)
	)
	(wire
		(pts
			(xy 149.86 44.45) (xy 149.86 46.99)
		)
		(stroke
			(width 0)
			(type default)
		)
	)
	(wire
		(pts
			(xy 270.51 54.61) (xy 262.89 54.61)
		)
		(stroke
			(width 0)
			(type default)
		)
	)
	(wire
		(pts
			(xy 165.1 54.61) (xy 172.72 54.61)
		)
		(stroke
			(width 0)
			(type default)
		)
	)
	(wire
		(pts
			(xy 260.35 129.54) (xy 242.57 129.54)
		)
		(stroke
			(width 0)
			(type default)
		)
	)
	(wire
		(pts
			(xy 247.65 78.74) (xy 247.65 62.23)
		)
		(stroke
			(width 0)
			(type default)
		)
	)
	(wire
		(pts
			(xy 260.35 99.06) (xy 242.57 99.06)
		)
		(stroke
			(width 0)
			(type default)
		)
	)
	(wire
		(pts
			(xy 242.57 154.94) (xy 260.35 154.94)
		)
		(stroke
			(width 0)
			(type default)
		)
	)
	(wire
		(pts
			(xy 165.1 86.36) (xy 187.96 86.36)
		)
		(stroke
			(width 0)
			(type default)
		)
	)
	(wire
		(pts
			(xy 278.13 44.45) (xy 278.13 46.99)
		)
		(stroke
			(width 0)
			(type default)
		)
	)
	(wire
		(pts
			(xy 187.96 134.62) (xy 146.05 134.62)
		)
		(stroke
			(width 0)
			(type default)
		)
	)
	(wire
		(pts
			(xy 149.86 52.07) (xy 149.86 54.61)
		)
		(stroke
			(width 0)
			(type default)
		)
	)
	(wire
		(pts
			(xy 165.1 180.34) (xy 187.96 180.34)
		)
		(stroke
			(width 0)
			(type default)
		)
	)
	(wire
		(pts
			(xy 242.57 177.8) (xy 260.35 177.8)
		)
		(stroke
			(width 0)
			(type default)
		)
	)
	(bus
		(pts
			(xy 163.83 191.77) (xy 163.83 199.39)
		)
		(stroke
			(width 0)
			(type default)
		)
	)
	(wire
		(pts
			(xy 142.24 44.45) (xy 149.86 44.45)
		)
		(stroke
			(width 0)
			(type default)
		)
	)
	(wire
		(pts
			(xy 260.35 106.68) (xy 242.57 106.68)
		)
		(stroke
			(width 0)
			(type default)
		)
	)
	(wire
		(pts
			(xy 242.57 190.5) (xy 260.35 190.5)
		)
		(stroke
			(width 0)
			(type default)
		)
	)
	(bus
		(pts
			(xy 261.62 113.03) (xy 261.62 115.57)
		)
		(stroke
			(width 0)
			(type default)
		)
	)
	(wire
		(pts
			(xy 255.27 54.61) (xy 255.27 52.07)
		)
		(stroke
			(width 0)
			(type default)
		)
	)
	(wire
		(pts
			(xy 157.48 54.61) (xy 165.1 54.61)
		)
		(stroke
			(width 0)
			(type default)
		)
	)
	(bus
		(pts
			(xy 261.62 80.01) (xy 261.62 82.55)
		)
		(stroke
			(width 0)
			(type default)
		)
	)
	(bus
		(pts
			(xy 261.62 179.07) (xy 261.62 181.61)
		)
		(stroke
			(width 0)
			(type default)
		)
	)
	(wire
		(pts
			(xy 165.1 91.44) (xy 187.96 91.44)
		)
		(stroke
			(width 0)
			(type default)
		)
	)
	(wire
		(pts
			(xy 242.57 203.2) (xy 243.84 203.2)
		)
		(stroke
			(width 0)
			(type default)
		)
	)
	(bus
		(pts
			(xy 157.48 207.01) (xy 162.56 207.01)
		)
		(stroke
			(width 0)
			(type default)
		)
	)
	(wire
		(pts
			(xy 260.35 116.84) (xy 242.57 116.84)
		)
		(stroke
			(width 0)
			(type default)
		)
	)
	(bus
		(pts
			(xy 160.02 74.93) (xy 162.56 74.93)
		)
		(stroke
			(width 0)
			(type default)
		)
	)
	(wire
		(pts
			(xy 149.86 44.45) (xy 157.48 44.45)
		)
		(stroke
			(width 0)
			(type default)
		)
	)
	(bus
		(pts
			(xy 163.83 90.17) (xy 163.83 92.71)
		)
		(stroke
			(width 0)
			(type default)
		)
	)
	(wire
		(pts
			(xy 278.13 54.61) (xy 270.51 54.61)
		)
		(stroke
			(width 0)
			(type default)
		)
	)
	(wire
		(pts
			(xy 165.1 44.45) (xy 172.72 44.45)
		)
		(stroke
			(width 0)
			(type default)
		)
	)
	(bus
		(pts
			(xy 261.62 181.61) (xy 261.62 184.15)
		)
		(stroke
			(width 0)
			(type default)
		)
	)
	(bus
		(pts
			(xy 261.62 196.85) (xy 261.62 199.39)
		)
		(stroke
			(width 0)
			(type default)
		)
	)
	(wire
		(pts
			(xy 285.75 44.45) (xy 278.13 44.45)
		)
		(stroke
			(width 0)
			(type default)
		)
	)
	(wire
		(pts
			(xy 285.75 52.07) (xy 285.75 54.61)
		)
		(stroke
			(width 0)
			(type default)
		)
	)
	(bus
		(pts
			(xy 144.78 113.03) (xy 144.78 123.19)
		)
		(stroke
			(width 0)
			(type default)
		)
	)
	(wire
		(pts
			(xy 242.57 78.74) (xy 247.65 78.74)
		)
		(stroke
			(width 0)
			(type default)
		)
	)
	(wire
		(pts
			(xy 260.35 124.46) (xy 242.57 124.46)
		)
		(stroke
			(width 0)
			(type default)
		)
	)
	(bus
		(pts
			(xy 261.62 158.75) (xy 261.62 171.45)
		)
		(stroke
			(width 0)
			(type default)
		)
	)
	(wire
		(pts
			(xy 260.35 96.52) (xy 242.57 96.52)
		)
		(stroke
			(width 0)
			(type default)
		)
	)
	(bus
		(pts
			(xy 163.83 92.71) (xy 163.83 95.25)
		)
		(stroke
			(width 0)
			(type default)
		)
	)
	(wire
		(pts
			(xy 270.51 54.61) (xy 270.51 52.07)
		)
		(stroke
			(width 0)
			(type default)
		)
	)
	(bus
		(pts
			(xy 261.62 191.77) (xy 261.62 194.31)
		)
		(stroke
			(width 0)
			(type default)
		)
	)
	(wire
		(pts
			(xy 304.8 44.45) (xy 300.99 44.45)
		)
		(stroke
			(width 0)
			(type default)
		)
	)
	(wire
		(pts
			(xy 142.24 54.61) (xy 134.62 54.61)
		)
		(stroke
			(width 0)
			(type default)
		)
	)
	(bus
		(pts
			(xy 144.78 109.22) (xy 143.51 107.95)
		)
		(stroke
			(width 0)
			(type default)
		)
	)
	(wire
		(pts
			(xy 260.35 121.92) (xy 242.57 121.92)
		)
		(stroke
			(width 0)
			(type default)
		)
	)
	(wire
		(pts
			(xy 165.1 106.68) (xy 187.96 106.68)
		)
		(stroke
			(width 0)
			(type default)
		)
	)
	(wire
		(pts
			(xy 242.57 187.96) (xy 260.35 187.96)
		)
		(stroke
			(width 0)
			(type default)
		)
	)
	(wire
		(pts
			(xy 262.89 52.07) (xy 262.89 54.61)
		)
		(stroke
			(width 0)
			(type default)
		)
	)
	(wire
		(pts
			(xy 242.57 139.7) (xy 260.35 139.7)
		)
		(stroke
			(width 0)
			(type default)
		)
	)
	(wire
		(pts
			(xy 260.35 134.62) (xy 242.57 134.62)
		)
		(stroke
			(width 0)
			(type default)
		)
	)
	(wire
		(pts
			(xy 285.75 54.61) (xy 278.13 54.61)
		)
		(stroke
			(width 0)
			(type default)
		)
	)
	(wire
		(pts
			(xy 242.57 74.93) (xy 243.84 74.93)
		)
		(stroke
			(width 0)
			(type default)
		)
	)
	(wire
		(pts
			(xy 243.84 219.71) (xy 255.27 219.71)
		)
		(stroke
			(width 0)
			(type default)
		)
	)
	(wire
		(pts
			(xy 270.51 173.99) (xy 270.51 175.26)
		)
		(stroke
			(width 0)
			(type default)
		)
	)
	(wire
		(pts
			(xy 157.48 46.99) (xy 157.48 44.45)
		)
		(stroke
			(width 0)
			(type default)
		)
	)
	(wire
		(pts
			(xy 165.1 198.12) (xy 187.96 198.12)
		)
		(stroke
			(width 0)
			(type default)
		)
	)
	(wire
		(pts
			(xy 300.99 54.61) (xy 300.99 52.07)
		)
		(stroke
			(width 0)
			(type default)
		)
	)
	(bus
		(pts
			(xy 261.62 130.81) (xy 261.62 133.35)
		)
		(stroke
			(width 0)
			(type default)
		)
	)
	(wire
		(pts
			(xy 242.57 195.58) (xy 260.35 195.58)
		)
		(stroke
			(width 0)
			(type default)
		)
	)
	(bus
		(pts
			(xy 163.83 76.2) (xy 163.83 77.47)
		)
		(stroke
			(width 0)
			(type default)
		)
	)
	(bus
		(pts
			(xy 261.62 153.67) (xy 261.62 156.21)
		)
		(stroke
			(width 0)
			(type default)
		)
	)
	(bus
		(pts
			(xy 157.48 144.78) (xy 162.56 144.78)
		)
		(stroke
			(width 0)
			(type default)
		)
	)
	(bus
		(pts
			(xy 261.62 205.74) (xy 262.89 207.01)
		)
		(stroke
			(width 0)
			(type default)
		)
	)
	(wire
		(pts
			(xy 172.72 44.45) (xy 172.72 46.99)
		)
		(stroke
			(width 0)
			(type default)
		)
	)
	(wire
		(pts
			(xy 187.96 139.7) (xy 166.37 139.7)
		)
		(stroke
			(width 0)
			(type default)
		)
	)
	(bus
		(pts
			(xy 163.83 85.09) (xy 163.83 87.63)
		)
		(stroke
			(width 0)
			(type default)
		)
	)
	(bus
		(pts
			(xy 261.62 85.09) (xy 261.62 87.63)
		)
		(stroke
			(width 0)
			(type default)
		)
	)
	(bus
		(pts
			(xy 261.62 189.23) (xy 261.62 191.77)
		)
		(stroke
			(width 0)
			(type default)
		)
	)
	(wire
		(pts
			(xy 255.27 44.45) (xy 247.65 44.45)
		)
		(stroke
			(width 0)
			(type default)
		)
	)
	(bus
		(pts
			(xy 261.62 147.32) (xy 270.51 147.32)
		)
		(stroke
			(width 0)
			(type default)
		)
	)
	(bus
		(pts
			(xy 163.83 142.24) (xy 163.83 139.7)
		)
		(stroke
			(width 0)
			(type default)
		)
	)
	(wire
		(pts
			(xy 142.24 54.61) (xy 149.86 54.61)
		)
		(stroke
			(width 0)
			(type default)
		)
	)
	(wire
		(pts
			(xy 255.27 210.82) (xy 255.27 213.36)
		)
		(stroke
			(width 0)
			(type default)
		)
	)
	(bus
		(pts
			(xy 261.62 87.63) (xy 261.62 90.17)
		)
		(stroke
			(width 0)
			(type default)
		)
	)
	(wire
		(pts
			(xy 187.96 137.16) (xy 166.37 137.16)
		)
		(stroke
			(width 0)
			(type default)
		)
	)
	(bus
		(pts
			(xy 261.62 138.43) (xy 261.62 140.97)
		)
		(stroke
			(width 0)
			(type default)
		)
	)
	(wire
		(pts
			(xy 243.84 203.2) (xy 243.84 219.71)
		)
		(stroke
			(width 0)
			(type default)
		)
	)
	(wire
		(pts
			(xy 262.89 44.45) (xy 255.27 44.45)
		)
		(stroke
			(width 0)
			(type default)
		)
	)
	(bus
		(pts
			(xy 261.62 151.13) (xy 261.62 153.67)
		)
		(stroke
			(width 0)
			(type default)
		)
	)
	(wire
		(pts
			(xy 293.37 54.61) (xy 285.75 54.61)
		)
		(stroke
			(width 0)
			(type default)
		)
	)
	(bus
		(pts
			(xy 261.62 201.93) (xy 261.62 205.74)
		)
		(stroke
			(width 0)
			(type default)
		)
	)
	(wire
		(pts
			(xy 262.89 44.45) (xy 262.89 46.99)
		)
		(stroke
			(width 0)
			(type default)
		)
	)
	(wire
		(pts
			(xy 270.51 44.45) (xy 262.89 44.45)
		)
		(stroke
			(width 0)
			(type default)
		)
	)
	(wire
		(pts
			(xy 293.37 54.61) (xy 293.37 52.07)
		)
		(stroke
			(width 0)
			(type default)
		)
	)
	(wire
		(pts
			(xy 146.05 177.8) (xy 187.96 177.8)
		)
		(stroke
			(width 0)
			(type default)
		)
	)
	(wire
		(pts
			(xy 260.35 83.82) (xy 242.57 83.82)
		)
		(stroke
			(width 0)
			(type default)
		)
	)
	(wire
		(pts
			(xy 304.8 41.91) (xy 304.8 44.45)
		)
		(stroke
			(width 0)
			(type default)
		)
	)
	(wire
		(pts
			(xy 165.1 44.45) (xy 165.1 46.99)
		)
		(stroke
			(width 0)
			(type default)
		)
	)
	(bus
		(pts
			(xy 261.62 102.87) (xy 261.62 105.41)
		)
		(stroke
			(width 0)
			(type default)
		)
	)
	(bus
		(pts
			(xy 163.83 76.2) (xy 162.56 74.93)
		)
		(stroke
			(width 0)
			(type default)
		)
	)
	(wire
		(pts
			(xy 260.35 111.76) (xy 242.57 111.76)
		)
		(stroke
			(width 0)
			(type default)
		)
	)
	(wire
		(pts
			(xy 255.27 62.23) (xy 255.27 64.77)
		)
		(stroke
			(width 0)
			(type default)
		)
	)
	(bus
		(pts
			(xy 262.89 74.93) (xy 270.51 74.93)
		)
		(stroke
			(width 0)
			(type default)
		)
	)
	(wire
		(pts
			(xy 247.65 54.61) (xy 247.65 52.07)
		)
		(stroke
			(width 0)
			(type default)
		)
	)
	(bus
		(pts
			(xy 261.62 120.65) (xy 261.62 123.19)
		)
		(stroke
			(width 0)
			(type default)
		)
	)
	(bus
		(pts
			(xy 261.62 184.15) (xy 261.62 186.69)
		)
		(stroke
			(width 0)
			(type default)
		)
	)
	(wire
		(pts
			(xy 134.62 54.61) (xy 134.62 55.88)
		)
		(stroke
			(width 0)
			(type default)
		)
	)
	(wire
		(pts
			(xy 278.13 54.61) (xy 278.13 52.07)
		)
		(stroke
			(width 0)
			(type default)
		)
	)
	(bus
		(pts
			(xy 163.83 176.53) (xy 163.83 181.61)
		)
		(stroke
			(width 0)
			(type default)
		)
	)
	(wire
		(pts
			(xy 180.34 54.61) (xy 180.34 52.07)
		)
		(stroke
			(width 0)
			(type default)
		)
	)
	(bus
		(pts
			(xy 144.78 171.45) (xy 144.78 176.53)
		)
		(stroke
			(width 0)
			(type default)
		)
	)
	(wire
		(pts
			(xy 293.37 44.45) (xy 285.75 44.45)
		)
		(stroke
			(width 0)
			(type default)
		)
	)
	(wire
		(pts
			(xy 247.65 46.99) (xy 247.65 44.45)
		)
		(stroke
			(width 0)
			(type default)
		)
	)
	(wire
		(pts
			(xy 255.27 69.85) (xy 255.27 71.12)
		)
		(stroke
			(width 0)
			(type default)
		)
	)
	(bus
		(pts
			(xy 261.62 135.89) (xy 261.62 138.43)
		)
		(stroke
			(width 0)
			(type default)
		)
	)
	(wire
		(pts
			(xy 260.35 101.6) (xy 242.57 101.6)
		)
		(stroke
			(width 0)
			(type default)
		)
	)
	(bus
		(pts
			(xy 261.62 92.71) (xy 261.62 95.25)
		)
		(stroke
			(width 0)
			(type default)
		)
	)
	(bus
		(pts
			(xy 261.62 140.97) (xy 261.62 143.51)
		)
		(stroke
			(width 0)
			(type default)
		)
	)
	(bus
		(pts
			(xy 163.83 77.47) (xy 163.83 80.01)
		)
		(stroke
			(width 0)
			(type default)
		)
	)
	(wire
		(pts
			(xy 180.34 46.99) (xy 180.34 44.45)
		)
		(stroke
			(width 0)
			(type default)
		)
	)
	(bus
		(pts
			(xy 261.62 143.51) (xy 261.62 147.32)
		)
		(stroke
			(width 0)
			(type default)
		)
	)
	(wire
		(pts
			(xy 260.35 86.36) (xy 242.57 86.36)
		)
		(stroke
			(width 0)
			(type default)
		)
	)
	(wire
		(pts
			(xy 165.1 54.61) (xy 165.1 52.07)
		)
		(stroke
			(width 0)
			(type default)
		)
	)
	(wire
		(pts
			(xy 185.42 74.93) (xy 187.96 74.93)
		)
		(stroke
			(width 0)
			(type default)
		)
	)
	(bus
		(pts
			(xy 163.83 189.23) (xy 163.83 191.77)
		)
		(stroke
			(width 0)
			(type default)
		)
	)
	(bus
		(pts
			(xy 144.78 133.35) (xy 144.78 171.45)
		)
		(stroke
			(width 0)
			(type default)
		)
	)
	(wire
		(pts
			(xy 165.1 99.06) (xy 187.96 99.06)
		)
		(stroke
			(width 0)
			(type default)
		)
	)
	(wire
		(pts
			(xy 242.57 180.34) (xy 260.35 180.34)
		)
		(stroke
			(width 0)
			(type default)
		)
	)
	(bus
		(pts
			(xy 261.62 133.35) (xy 261.62 135.89)
		)
		(stroke
			(width 0)
			(type default)
		)
	)
	(wire
		(pts
			(xy 149.86 54.61) (xy 157.48 54.61)
		)
		(stroke
			(width 0)
			(type default)
		)
	)
	(bus
		(pts
			(xy 142.24 107.95) (xy 143.51 107.95)
		)
		(stroke
			(width 0)
			(type default)
		)
	)
	(bus
		(pts
			(xy 163.83 87.63) (xy 163.83 90.17)
		)
		(stroke
			(width 0)
			(type default)
		)
	)
	(bus
		(pts
			(xy 261.62 128.27) (xy 261.62 130.81)
		)
		(stroke
			(width 0)
			(type default)
		)
	)
	(wire
		(pts
			(xy 260.35 88.9) (xy 242.57 88.9)
		)
		(stroke
			(width 0)
			(type default)
		)
	)
	(wire
		(pts
			(xy 300.99 44.45) (xy 300.99 46.99)
		)
		(stroke
			(width 0)
			(type default)
		)
	)
	(wire
		(pts
			(xy 260.35 119.38) (xy 242.57 119.38)
		)
		(stroke
			(width 0)
			(type default)
		)
	)
	(wire
		(pts
			(xy 165.1 78.74) (xy 187.96 78.74)
		)
		(stroke
			(width 0)
			(type default)
		)
	)
	(wire
		(pts
			(xy 285.75 44.45) (xy 285.75 46.99)
		)
		(stroke
			(width 0)
			(type default)
		)
	)
	(bus
		(pts
			(xy 261.62 125.73) (xy 261.62 128.27)
		)
		(stroke
			(width 0)
			(type default)
		)
	)
	(wire
		(pts
			(xy 180.34 44.45) (xy 185.42 44.45)
		)
		(stroke
			(width 0)
			(type default)
		)
	)
	(wire
		(pts
			(xy 242.57 200.66) (xy 260.35 200.66)
		)
		(stroke
			(width 0)
			(type default)
		)
	)
	(wire
		(pts
			(xy 270.51 175.26) (xy 270.51 177.8)
		)
		(stroke
			(width 0)
			(type default)
		)
	)
	(wire
		(pts
			(xy 255.27 218.44) (xy 255.27 219.71)
		)
		(stroke
			(width 0)
			(type default)
		)
	)
	(bus
		(pts
			(xy 262.89 207.01) (xy 270.51 207.01)
		)
		(stroke
			(width 0)
			(type default)
		)
	)
	(bus
		(pts
			(xy 261.62 199.39) (xy 261.62 201.93)
		)
		(stroke
			(width 0)
			(type default)
		)
	)
	(wire
		(pts
			(xy 242.57 175.26) (xy 270.51 175.26)
		)
		(stroke
			(width 0)
			(type default)
		)
	)
	(wire
		(pts
			(xy 242.57 198.12) (xy 260.35 198.12)
		)
		(stroke
			(width 0)
			(type default)
		)
	)
	(bus
		(pts
			(xy 163.83 181.61) (xy 163.83 189.23)
		)
		(stroke
			(width 0)
			(type default)
		)
	)
	(bus
		(pts
			(xy 261.62 156.21) (xy 261.62 158.75)
		)
		(stroke
			(width 0)
			(type default)
		)
	)
	(label "SYS.CLK_N"
		(at 177.8 139.7 180)
		(effects
			(font
				(size 1.27 1.27)
			)
			(justify right bottom)
		)
	)
	(label "SD_CARD.DAT0"
		(at 161.29 177.8 180)
		(effects
			(font
				(size 1.27 1.27)
			)
			(justify right bottom)
		)
	)
	(label "DDR.BA1"
		(at 255.27 132.08 180)
		(effects
			(font
				(size 1.27 1.27)
			)
			(justify right bottom)
		)
	)
	(label "USER_IO.BUTTON0"
		(at 186.69 101.6 180)
		(effects
			(font
				(size 1.27 1.27)
			)
			(justify right bottom)
		)
	)
	(label "DDR.DQ0"
		(at 246.38 198.12 0)
		(effects
			(font
				(size 1.27 1.27)
			)
			(justify left bottom)
		)
	)
	(label "USER_IO.DIP_SW0"
		(at 186.69 78.74 180)
		(effects
			(font
				(size 1.27 1.27)
			)
			(justify right bottom)
		)
	)
	(label "SD_CARD.~{CD}"
		(at 161.29 172.72 180)
		(effects
			(font
				(size 1.27 1.27)
			)
			(justify right bottom)
		)
	)
	(label "DDR.DM"
		(at 246.38 172.72 0)
		(effects
			(font
				(size 1.27 1.27)
			)
			(justify left bottom)
		)
	)
	(label "DDR.A10"
		(at 246.38 99.06 0)
		(effects
			(font
				(size 1.27 1.27)
			)
			(justify left bottom)
		)
	)
	(label "DDR.~{RESET}"
		(at 246.38 142.24 0)
		(effects
			(font
				(size 1.27 1.27)
			)
			(justify left bottom)
		)
	)
	(label "DDR.DQ2"
		(at 246.38 190.5 0)
		(effects
			(font
				(size 1.27 1.27)
			)
			(justify left bottom)
		)
	)
	(label "DDR.A11"
		(at 246.38 96.52 0)
		(effects
			(font
				(size 1.27 1.27)
			)
			(justify left bottom)
		)
	)
	(label "USER_IO.DIP_SW3"
		(at 186.69 93.98 180)
		(effects
			(font
				(size 1.27 1.27)
			)
			(justify right bottom)
		)
	)
	(label "DDR.DQ5"
		(at 246.38 193.04 0)
		(effects
			(font
				(size 1.27 1.27)
			)
			(justify left bottom)
		)
	)
	(label "USR_FLASH_0.DQ3"
		(at 186.69 198.12 180)
		(effects
			(font
				(size 1.27 1.27)
			)
			(justify right bottom)
		)
	)
	(label "SD_CARD.DAT1"
		(at 161.29 134.62 180)
		(effects
			(font
				(size 1.27 1.27)
			)
			(justify right bottom)
		)
	)
	(label "USR_FLASH_0.~{CS}"
		(at 186.69 175.26 180)
		(effects
			(font
				(size 1.27 1.27)
			)
			(justify right bottom)
		)
	)
	(label "DDR.DQ6"
		(at 246.38 200.66 0)
		(effects
			(font
				(size 1.27 1.27)
			)
			(justify left bottom)
		)
	)
	(label "DDR_VRP"
		(at 245.11 219.71 0)
		(effects
			(font
				(size 1.27 1.27)
			)
			(justify left bottom)
		)
	)
	(label "SD_CARD.DAT2"
		(at 161.29 129.54 180)
		(effects
			(font
				(size 1.27 1.27)
			)
			(justify right bottom)
		)
	)
	(label "DDR.A12"
		(at 246.38 88.9 0)
		(effects
			(font
				(size 1.27 1.27)
			)
			(justify left bottom)
		)
	)
	(label "SD_CARD.DAT3"
		(at 161.29 111.76 180)
		(effects
			(font
				(size 1.27 1.27)
			)
			(justify right bottom)
		)
	)
	(label "DDR.ODT"
		(at 246.38 160.02 0)
		(effects
			(font
				(size 1.27 1.27)
			)
			(justify left bottom)
		)
	)
	(label "DDR.A8"
		(at 246.38 104.14 0)
		(effects
			(font
				(size 1.27 1.27)
			)
			(justify left bottom)
		)
	)
	(label "USER_IO.DIP_SW5"
		(at 186.69 109.22 180)
		(effects
			(font
				(size 1.27 1.27)
			)
			(justify right bottom)
		)
	)
	(label "USR_FLASH_0.CLK"
		(at 186.69 190.5 180)
		(effects
			(font
				(size 1.27 1.27)
			)
			(justify right bottom)
		)
	)
	(label "DDR.DQS_N"
		(at 246.38 185.42 0)
		(effects
			(font
				(size 1.27 1.27)
			)
			(justify left bottom)
		)
	)
	(label "USER_IO.BUTTON2"
		(at 186.69 99.06 180)
		(effects
			(font
				(size 1.27 1.27)
			)
			(justify right bottom)
		)
	)
	(label "DDR.BA0"
		(at 255.27 134.62 180)
		(effects
			(font
				(size 1.27 1.27)
			)
			(justify right bottom)
		)
	)
	(label "SYS.CLK_P"
		(at 177.8 137.16 180)
		(effects
			(font
				(size 1.27 1.27)
			)
			(justify right bottom)
		)
	)
	(label "DDR.DQ4"
		(at 246.38 180.34 0)
		(effects
			(font
				(size 1.27 1.27)
			)
			(justify left bottom)
		)
	)
	(label "DDR.DQS_P"
		(at 246.38 182.88 0)
		(effects
			(font
				(size 1.27 1.27)
			)
			(justify left bottom)
		)
	)
	(label "USR_FLASH_0.DQ2"
		(at 186.69 200.66 180)
		(effects
			(font
				(size 1.27 1.27)
			)
			(justify right bottom)
		)
	)
	(label "DDR.~{RAS}"
		(at 246.38 139.7 0)
		(effects
			(font
				(size 1.27 1.27)
			)
			(justify left bottom)
		)
	)
	(label "USER_IO.DIP_SW2"
		(at 186.69 86.36 180)
		(effects
			(font
				(size 1.27 1.27)
			)
			(justify right bottom)
		)
	)
	(label "DDR.A7"
		(at 246.38 106.68 0)
		(effects
			(font
				(size 1.27 1.27)
			)
			(justify left bottom)
		)
	)
	(label "USER_IO.BUTTON3"
		(at 186.69 96.52 180)
		(effects
			(font
				(size 1.27 1.27)
			)
			(justify right bottom)
		)
	)
	(label "DDR.DQ3"
		(at 246.38 187.96 0)
		(effects
			(font
				(size 1.27 1.27)
			)
			(justify left bottom)
		)
	)
	(label "DDR.A3"
		(at 246.38 119.38 0)
		(effects
			(font
				(size 1.27 1.27)
			)
			(justify left bottom)
		)
	)
	(label "DDR.~{WE}"
		(at 246.38 152.4 0)
		(effects
			(font
				(size 1.27 1.27)
			)
			(justify left bottom)
		)
	)
	(label "DDR.CK_N"
		(at 246.38 93.98 0)
		(effects
			(font
				(size 1.27 1.27)
			)
			(justify left bottom)
		)
	)
	(label "DDR.BA2"
		(at 255.27 129.54 180)
		(effects
			(font
				(size 1.27 1.27)
			)
			(justify right bottom)
		)
	)
	(label "USR_FLASH_0.DQ1"
		(at 186.69 180.34 180)
		(effects
			(font
				(size 1.27 1.27)
			)
			(justify right bottom)
		)
	)
	(label "DDR.A15"
		(at 246.38 81.28 0)
		(effects
			(font
				(size 1.27 1.27)
			)
			(justify left bottom)
		)
	)
	(label "DDR_VRN"
		(at 247.65 62.23 0)
		(effects
			(font
				(size 1.27 1.27)
			)
			(justify left bottom)
		)
	)
	(label "DDR.A2"
		(at 246.38 121.92 0)
		(effects
			(font
				(size 1.27 1.27)
			)
			(justify left bottom)
		)
	)
	(label "DDR.DQ1"
		(at 246.38 195.58 0)
		(effects
			(font
				(size 1.27 1.27)
			)
			(justify left bottom)
		)
	)
	(label "DDR.~{CAS}"
		(at 246.38 137.16 0)
		(effects
			(font
				(size 1.27 1.27)
			)
			(justify left bottom)
		)
	)
	(label "DDR.CKE"
		(at 246.38 157.48 0)
		(effects
			(font
				(size 1.27 1.27)
			)
			(justify left bottom)
		)
	)
	(label "DDR.A5"
		(at 246.38 114.3 0)
		(effects
			(font
				(size 1.27 1.27)
			)
			(justify left bottom)
		)
	)
	(label "DDR.~{CS}"
		(at 246.38 154.94 0)
		(effects
			(font
				(size 1.27 1.27)
			)
			(justify left bottom)
		)
	)
	(label "USER_IO.DIP_SW7"
		(at 186.69 81.28 180)
		(effects
			(font
				(size 1.27 1.27)
			)
			(justify right bottom)
		)
	)
	(label "SD_CARD.CLK"
		(at 161.29 124.46 180)
		(effects
			(font
				(size 1.27 1.27)
			)
			(justify right bottom)
		)
	)
	(label "DDR.A6"
		(at 246.38 111.76 0)
		(effects
			(font
				(size 1.27 1.27)
			)
			(justify left bottom)
		)
	)
	(label "DDR.A1"
		(at 246.38 124.46 0)
		(effects
			(font
				(size 1.27 1.27)
			)
			(justify left bottom)
		)
	)
	(label "DDR.A4"
		(at 246.38 116.84 0)
		(effects
			(font
				(size 1.27 1.27)
			)
			(justify left bottom)
		)
	)
	(label "DDR.DQ7"
		(at 246.38 177.8 0)
		(effects
			(font
				(size 1.27 1.27)
			)
			(justify left bottom)
		)
	)
	(label "DDR.CK_P"
		(at 246.38 91.44 0)
		(effects
			(font
				(size 1.27 1.27)
			)
			(justify left bottom)
		)
	)
	(label "DDR.A9"
		(at 246.38 101.6 0)
		(effects
			(font
				(size 1.27 1.27)
			)
			(justify left bottom)
		)
	)
	(label "SD_CARD.CMD"
		(at 161.29 114.3 180)
		(effects
			(font
				(size 1.27 1.27)
			)
			(justify right bottom)
		)
	)
	(label "DDR.A14"
		(at 246.38 83.82 0)
		(effects
			(font
				(size 1.27 1.27)
			)
			(justify left bottom)
		)
	)
	(label "DDR.A13"
		(at 246.38 86.36 0)
		(effects
			(font
				(size 1.27 1.27)
			)
			(justify left bottom)
		)
	)
	(label "USER_IO.BUTTON1"
		(at 186.69 104.14 180)
		(effects
			(font
				(size 1.27 1.27)
			)
			(justify right bottom)
		)
	)
	(label "USER_IO.DIP_SW4"
		(at 186.69 106.68 180)
		(effects
			(font
				(size 1.27 1.27)
			)
			(justify right bottom)
		)
	)
	(label "DDR.A0"
		(at 246.38 127 0)
		(effects
			(font
				(size 1.27 1.27)
			)
			(justify left bottom)
		)
	)
	(label "USER_IO.DIP_SW6"
		(at 186.69 91.44 180)
		(effects
			(font
				(size 1.27 1.27)
			)
			(justify right bottom)
		)
	)
	(label "USR_FLASH_0.DQ0"
		(at 186.69 187.96 180)
		(effects
			(font
				(size 1.27 1.27)
			)
			(justify right bottom)
		)
	)
	(label "USER_IO.DIP_SW1"
		(at 186.69 88.9 180)
		(effects
			(font
				(size 1.27 1.27)
			)
			(justify right bottom)
		)
	)
	(hierarchical_label "DDR{DDR3_DRAM}"
		(shape input)
		(at 270.51 74.93 0)
		(effects
			(font
				(size 1.27 1.27)
			)
			(justify left)
		)
	)
	(hierarchical_label "DDR{DDR3_DRAM}"
		(shape input)
		(at 270.51 207.01 0)
		(effects
			(font
				(size 1.27 1.27)
			)
			(justify left)
		)
	)
	(hierarchical_label "SD_CARD{SD-CARD}"
		(shape bidirectional)
		(at 142.24 107.95 180)
		(effects
			(font
				(size 1.27 1.27)
			)
			(justify right)
		)
	)
	(hierarchical_label "USR_FLASH_0{SPI-FLASH}"
		(shape bidirectional)
		(at 157.48 207.01 180)
		(effects
			(font
				(size 1.27 1.27)
			)
			(justify right)
		)
	)
	(hierarchical_label "USER_IO{USER-IO}"
		(shape bidirectional)
		(at 160.02 74.93 180)
		(effects
			(font
				(size 1.27 1.27)
			)
			(justify right)
		)
	)
	(hierarchical_label "DDR{DDR3_DRAM}"
		(shape input)
		(at 270.51 147.32 0)
		(effects
			(font
				(size 1.27 1.27)
			)
			(justify left)
		)
	)
	(hierarchical_label "SYS{CLK}"
		(shape input)
		(at 157.48 144.78 180)
		(effects
			(font
				(size 1.27 1.27)
			)
			(justify right)
		)
	)
	(hierarchical_label "LVDS_XO_200M_ENA"
		(shape output)
		(at 185.42 127 180)
		(effects
			(font
				(size 1.27 1.27)
			)
			(justify right)
		)
	)
	(symbol
		(lib_id "antmicroCapacitors0402:C_100n_0402")
		(at 270.51 116.84 90)
		(unit 1)
		(exclude_from_sim no)
		(in_bom yes)
		(on_board yes)
		(dnp no)
		(property "Reference" "C374"
			(at 271.145 112.395 90)
			(effects
				(font
					(size 1.27 1.27)
				)
				(justify right)
			)
		)
		(property "Value" "C_100n_0402"
			(at 280.67 96.52 0)
			(effects
				(font
					(size 1.27 1.27)
					(thickness 0.15)
				)
				(justify left bottom)
				(hide yes)
			)
		)
		(property "Footprint" "antmicro-footprints:C_0402_1005Metric"
			(at 283.21 96.52 0)
			(effects
				(font
					(size 1.27 1.27)
					(thickness 0.15)
				)
				(justify left bottom)
				(hide yes)
			)
		)
		(property "Datasheet" "https://www.murata.com/products/productdetail?partno=GRM155R61H104KE14%23"
			(at 285.75 96.52 0)
			(effects
				(font
					(size 1.27 1.27)
					(thickness 0.15)
				)
				(justify left bottom)
				(hide yes)
			)
		)
		(property "Description" ""
			(at 270.51 116.84 0)
			(effects
				(font
					(size 1.27 1.27)
				)
			)
		)
		(property "Manufacturer" "Murata"
			(at 290.83 96.52 0)
			(effects
				(font
					(size 1.27 1.27)
					(thickness 0.15)
				)
				(justify left bottom)
				(hide yes)
			)
		)
		(property "MPN" "GRM155R61H104KE14D"
			(at 288.29 96.52 0)
			(effects
				(font
					(size 1.27 1.27)
					(thickness 0.15)
				)
				(justify left bottom)
				(hide yes)
			)
		)
		(property "Val" "100n"
			(at 271.145 116.205 90)
			(effects
				(font
					(size 1.27 1.27)
					(thickness 0.15)
				)
				(justify right)
			)
		)
		(property "License" "Apache-2.0"
			(at 293.37 96.52 0)
			(effects
				(font
					(size 1.27 1.27)
					(thickness 0.15)
				)
				(justify left bottom)
				(hide yes)
			)
		)
		(property "Author" "Antmicro"
			(at 295.91 96.52 0)
			(effects
				(font
					(size 1.27 1.27)
					(thickness 0.15)
				)
				(justify left bottom)
				(hide yes)
			)
		)
		(property "Voltage" "50V"
			(at 298.45 96.52 0)
			(effects
				(font
					(size 1.27 1.27)
				)
				(justify left bottom)
				(hide yes)
			)
		)
		(property "Dielectric" "X5R"
			(at 300.99 96.52 0)
			(effects
				(font
					(size 1.27 1.27)
				)
				(justify left bottom)
				(hide yes)
			)
		)
		(pin "1"
		)
		(pin "2"
		)
		(instances
			(project "k410t-devboard"
				(path ""
					(reference "C374")
					(unit 1)
				)
			)
		)
	)
	(symbol
		(lib_id "antmicroCapacitors0402:C_100n_0402")
		(at 157.48 52.07 270)
		(mirror x)
		(unit 1)
		(exclude_from_sim no)
		(in_bom yes)
		(on_board yes)
		(dnp no)
		(property "Reference" "C90"
			(at 156.845 47.625 90)
			(effects
				(font
					(size 1.27 1.27)
				)
				(justify right)
			)
		)
		(property "Value" "C_100n_0402"
			(at 147.32 31.75 0)
			(effects
				(font
					(size 1.27 1.27)
					(thickness 0.15)
				)
				(justify left bottom)
				(hide yes)
			)
		)
		(property "Footprint" "antmicro-footprints:C_0402_1005Metric"
			(at 144.78 31.75 0)
			(effects
				(font
					(size 1.27 1.27)
					(thickness 0.15)
				)
				(justify left bottom)
				(hide yes)
			)
		)
		(property "Datasheet" "https://www.murata.com/products/productdetail?partno=GRM155R61H104KE14%23"
			(at 142.24 31.75 0)
			(effects
				(font
					(size 1.27 1.27)
					(thickness 0.15)
				)
				(justify left bottom)
				(hide yes)
			)
		)
		(property "Description" ""
			(at 157.48 52.07 0)
			(effects
				(font
					(size 1.27 1.27)
				)
			)
		)
		(property "Manufacturer" "Murata"
			(at 137.16 31.75 0)
			(effects
				(font
					(size 1.27 1.27)
					(thickness 0.15)
				)
				(justify left bottom)
				(hide yes)
			)
		)
		(property "MPN" "GRM155R61H104KE14D"
			(at 139.7 31.75 0)
			(effects
				(font
					(size 1.27 1.27)
					(thickness 0.15)
				)
				(justify left bottom)
				(hide yes)
			)
		)
		(property "Val" "100n"
			(at 156.845 51.435 90)
			(effects
				(font
					(size 1.27 1.27)
					(thickness 0.15)
				)
				(justify right)
			)
		)
		(property "License" "Apache-2.0"
			(at 134.62 31.75 0)
			(effects
				(font
					(size 1.27 1.27)
					(thickness 0.15)
				)
				(justify left bottom)
				(hide yes)
			)
		)
		(property "Author" "Antmicro"
			(at 132.08 31.75 0)
			(effects
				(font
					(size 1.27 1.27)
					(thickness 0.15)
				)
				(justify left bottom)
				(hide yes)
			)
		)
		(property "Voltage" "50V"
			(at 129.54 31.75 0)
			(effects
				(font
					(size 1.27 1.27)
				)
				(justify left bottom)
				(hide yes)
			)
		)
		(property "Dielectric" "X5R"
			(at 127 31.75 0)
			(effects
				(font
					(size 1.27 1.27)
				)
				(justify left bottom)
				(hide yes)
			)
		)
		(pin "1"
		)
		(pin "2"
		)
		(instances
			(project "k410t-devboard"
				(path ""
					(reference "C90")
					(unit 1)
				)
			)
		)
	)
	(symbol
		(lib_id "antmicroCapacitors0402:C_100n_0402")
		(at 149.86 52.07 270)
		(mirror x)
		(unit 1)
		(exclude_from_sim no)
		(in_bom yes)
		(on_board yes)
		(dnp no)
		(property "Reference" "C95"
			(at 149.225 47.625 90)
			(effects
				(font
					(size 1.27 1.27)
				)
				(justify right)
			)
		)
		(property "Value" "C_100n_0402"
			(at 139.7 31.75 0)
			(effects
				(font
					(size 1.27 1.27)
					(thickness 0.15)
				)
				(justify left bottom)
				(hide yes)
			)
		)
		(property "Footprint" "antmicro-footprints:C_0402_1005Metric"
			(at 137.16 31.75 0)
			(effects
				(font
					(size 1.27 1.27)
					(thickness 0.15)
				)
				(justify left bottom)
				(hide yes)
			)
		)
		(property "Datasheet" "https://www.murata.com/products/productdetail?partno=GRM155R61H104KE14%23"
			(at 134.62 31.75 0)
			(effects
				(font
					(size 1.27 1.27)
					(thickness 0.15)
				)
				(justify left bottom)
				(hide yes)
			)
		)
		(property "Description" ""
			(at 149.86 52.07 0)
			(effects
				(font
					(size 1.27 1.27)
				)
			)
		)
		(property "Manufacturer" "Murata"
			(at 129.54 31.75 0)
			(effects
				(font
					(size 1.27 1.27)
					(thickness 0.15)
				)
				(justify left bottom)
				(hide yes)
			)
		)
		(property "MPN" "GRM155R61H104KE14D"
			(at 132.08 31.75 0)
			(effects
				(font
					(size 1.27 1.27)
					(thickness 0.15)
				)
				(justify left bottom)
				(hide yes)
			)
		)
		(property "Val" "100n"
			(at 149.225 51.435 90)
			(effects
				(font
					(size 1.27 1.27)
					(thickness 0.15)
				)
				(justify right)
			)
		)
		(property "License" "Apache-2.0"
			(at 127 31.75 0)
			(effects
				(font
					(size 1.27 1.27)
					(thickness 0.15)
				)
				(justify left bottom)
				(hide yes)
			)
		)
		(property "Author" "Antmicro"
			(at 124.46 31.75 0)
			(effects
				(font
					(size 1.27 1.27)
					(thickness 0.15)
				)
				(justify left bottom)
				(hide yes)
			)
		)
		(property "Voltage" "50V"
			(at 121.92 31.75 0)
			(effects
				(font
					(size 1.27 1.27)
				)
				(justify left bottom)
				(hide yes)
			)
		)
		(property "Dielectric" "X5R"
			(at 119.38 31.75 0)
			(effects
				(font
					(size 1.27 1.27)
				)
				(justify left bottom)
				(hide yes)
			)
		)
		(pin "1"
		)
		(pin "2"
		)
		(instances
			(project "k410t-devboard"
				(path ""
					(reference "C95")
					(unit 1)
				)
			)
		)
	)
	(symbol
		(lib_id "antmicroCapacitors0603:C_47u_0603")
		(at 134.62 46.99 270)
		(unit 1)
		(exclude_from_sim no)
		(in_bom yes)
		(on_board yes)
		(dnp no)
		(property "Reference" "C108"
			(at 133.985 47.625 90)
			(effects
				(font
					(size 1.27 1.27)
				)
				(justify right)
			)
		)
		(property "Value" "C_47u_0603"
			(at 124.46 67.31 0)
			(effects
				(font
					(size 1.27 1.27)
					(thickness 0.15)
				)
				(justify left bottom)
				(hide yes)
			)
		)
		(property "Footprint" "antmicro-footprints:C_0603_1608Metric"
			(at 121.92 67.31 0)
			(effects
				(font
					(size 1.27 1.27)
					(thickness 0.15)
				)
				(justify left bottom)
				(hide yes)
			)
		)
		(property "Datasheet" "https://www.murata.com/products/productdetail?partno=GRM188R60J476ME15%23"
			(at 119.38 67.31 0)
			(effects
				(font
					(size 1.27 1.27)
					(thickness 0.15)
				)
				(justify left bottom)
				(hide yes)
			)
		)
		(property "Description" ""
			(at 134.62 46.99 0)
			(effects
				(font
					(size 1.27 1.27)
				)
			)
		)
		(property "Manufacturer" "Murata"
			(at 114.3 67.31 0)
			(effects
				(font
					(size 1.27 1.27)
					(thickness 0.15)
				)
				(justify left bottom)
				(hide yes)
			)
		)
		(property "MPN" "GRM188R60J476ME15D"
			(at 116.84 67.31 0)
			(effects
				(font
					(size 1.27 1.27)
					(thickness 0.15)
				)
				(justify left bottom)
				(hide yes)
			)
		)
		(property "Val" "47u"
			(at 133.985 51.4477 90)
			(effects
				(font
					(size 1.27 1.27)
					(thickness 0.15)
				)
				(justify right)
			)
		)
		(property "License" "Apache-2.0"
			(at 111.76 67.31 0)
			(effects
				(font
					(size 1.27 1.27)
					(thickness 0.15)
				)
				(justify left bottom)
				(hide yes)
			)
		)
		(property "Author" "Antmicro"
			(at 109.22 67.31 0)
			(effects
				(font
					(size 1.27 1.27)
					(thickness 0.15)
				)
				(justify left bottom)
				(hide yes)
			)
		)
		(property "Voltage" ""
			(at 106.68 67.31 0)
			(effects
				(font
					(size 1.27 1.27)
				)
				(justify left bottom)
				(hide yes)
			)
		)
		(property "Dielectric" ""
			(at 104.14 67.31 0)
			(effects
				(font
					(size 1.27 1.27)
				)
				(justify left bottom)
				(hide yes)
			)
		)
		(pin "1"
		)
		(pin "2"
		)
		(instances
			(project "k410t-devboard"
				(path ""
					(reference "C108")
					(unit 1)
				)
			)
		)
	)
	(symbol
		(lib_id "antmicroCapacitors0402:C_100n_0402")
		(at 262.89 52.07 90)
		(unit 1)
		(exclude_from_sim no)
		(in_bom yes)
		(on_board yes)
		(dnp no)
		(property "Reference" "C79"
			(at 263.525 47.625 90)
			(effects
				(font
					(size 1.27 1.27)
				)
				(justify right)
			)
		)
		(property "Value" "C_100n_0402"
			(at 273.05 31.75 0)
			(effects
				(font
					(size 1.27 1.27)
					(thickness 0.15)
				)
				(justify left bottom)
				(hide yes)
			)
		)
		(property "Footprint" "antmicro-footprints:C_0402_1005Metric"
			(at 275.59 31.75 0)
			(effects
				(font
					(size 1.27 1.27)
					(thickness 0.15)
				)
				(justify left bottom)
				(hide yes)
			)
		)
		(property "Datasheet" "https://www.murata.com/products/productdetail?partno=GRM155R61H104KE14%23"
			(at 278.13 31.75 0)
			(effects
				(font
					(size 1.27 1.27)
					(thickness 0.15)
				)
				(justify left bottom)
				(hide yes)
			)
		)
		(property "Description" ""
			(at 262.89 52.07 0)
			(effects
				(font
					(size 1.27 1.27)
				)
			)
		)
		(property "Manufacturer" "Murata"
			(at 283.21 31.75 0)
			(effects
				(font
					(size 1.27 1.27)
					(thickness 0.15)
				)
				(justify left bottom)
				(hide yes)
			)
		)
		(property "MPN" "GRM155R61H104KE14D"
			(at 280.67 31.75 0)
			(effects
				(font
					(size 1.27 1.27)
					(thickness 0.15)
				)
				(justify left bottom)
				(hide yes)
			)
		)
		(property "Val" "100n"
			(at 263.525 51.435 90)
			(effects
				(font
					(size 1.27 1.27)
					(thickness 0.15)
				)
				(justify right)
			)
		)
		(property "License" "Apache-2.0"
			(at 285.75 31.75 0)
			(effects
				(font
					(size 1.27 1.27)
					(thickness 0.15)
				)
				(justify left bottom)
				(hide yes)
			)
		)
		(property "Author" "Antmicro"
			(at 288.29 31.75 0)
			(effects
				(font
					(size 1.27 1.27)
					(thickness 0.15)
				)
				(justify left bottom)
				(hide yes)
			)
		)
		(property "Voltage" "50V"
			(at 290.83 31.75 0)
			(effects
				(font
					(size 1.27 1.27)
				)
				(justify left bottom)
				(hide yes)
			)
		)
		(property "Dielectric" "X5R"
			(at 293.37 31.75 0)
			(effects
				(font
					(size 1.27 1.27)
				)
				(justify left bottom)
				(hide yes)
			)
		)
		(pin "1"
		)
		(pin "2"
		)
		(instances
			(project "k410t-devboard"
				(path ""
					(reference "C79")
					(unit 1)
				)
			)
		)
	)
	(symbol
		(lib_id "antmicroResistors0402:R_80R6_0402_EIA")
		(at 255.27 69.85 90)
		(unit 1)
		(exclude_from_sim no)
		(in_bom yes)
		(on_board yes)
		(dnp no)
		(property "Reference" "R339"
			(at 256.54 66.04 90)
			(effects
				(font
					(size 1.27 1.27)
				)
				(justify right)
			)
		)
		(property "Value" "R_80R6_0402_EIA"
			(at 267.97 49.53 0)
			(effects
				(font
					(size 1.27 1.27)
					(thickness 0.15)
				)
				(justify left bottom)
				(hide yes)
			)
		)
		(property "Footprint" "antmicro-footprints:R_0402_1005Metric_EIA"
			(at 270.51 49.53 0)
			(effects
				(font
					(size 1.27 1.27)
					(thickness 0.15)
				)
				(justify left bottom)
				(hide yes)
			)
		)
		(property "Datasheet" "https://www.bourns.com/docs/product-datasheets/cr.pdf"
			(at 273.05 49.53 0)
			(effects
				(font
					(size 1.27 1.27)
					(thickness 0.15)
				)
				(justify left bottom)
				(hide yes)
			)
		)
		(property "Description" ""
			(at 255.27 69.85 0)
			(effects
				(font
					(size 1.27 1.27)
				)
			)
		)
		(property "Manufacturer" "Multicomp Pro"
			(at 278.13 49.53 0)
			(effects
				(font
					(size 1.27 1.27)
					(thickness 0.15)
				)
				(justify left bottom)
				(hide yes)
			)
		)
		(property "MPN" "MC00625W0402180R6"
			(at 275.59 49.53 0)
			(effects
				(font
					(size 1.27 1.27)
					(thickness 0.15)
				)
				(justify left bottom)
				(hide yes)
			)
		)
		(property "Val" "80R6"
			(at 256.54 68.58 90)
			(effects
				(font
					(size 1.27 1.27)
					(thickness 0.15)
				)
				(justify right)
			)
		)
		(property "License" "Apache-2.0"
			(at 280.67 49.53 0)
			(effects
				(font
					(size 1.27 1.27)
					(thickness 0.15)
				)
				(justify left bottom)
				(hide yes)
			)
		)
		(property "Author" "Antmicro"
			(at 283.21 49.53 0)
			(effects
				(font
					(size 1.27 1.27)
					(thickness 0.15)
				)
				(justify left bottom)
				(hide yes)
			)
		)
		(property "Tolerance" "1%"
			(at 265.43 49.53 0)
			(effects
				(font
					(size 1.27 1.27)
				)
				(justify left bottom)
				(hide yes)
			)
		)
		(pin "1"
		)
		(pin "2"
		)
		(instances
			(project "k410t-devboard"
				(path ""
					(reference "R339")
					(unit 1)
				)
			)
		)
	)
	(symbol
		(lib_id "antmicroCapacitors0402:C_100n_0402")
		(at 285.75 52.07 90)
		(unit 1)
		(exclude_from_sim no)
		(in_bom yes)
		(on_board yes)
		(dnp no)
		(property "Reference" "C96"
			(at 286.385 47.625 90)
			(effects
				(font
					(size 1.27 1.27)
				)
				(justify right)
			)
		)
		(property "Value" "C_100n_0402"
			(at 295.91 31.75 0)
			(effects
				(font
					(size 1.27 1.27)
					(thickness 0.15)
				)
				(justify left bottom)
				(hide yes)
			)
		)
		(property "Footprint" "antmicro-footprints:C_0402_1005Metric"
			(at 298.45 31.75 0)
			(effects
				(font
					(size 1.27 1.27)
					(thickness 0.15)
				)
				(justify left bottom)
				(hide yes)
			)
		)
		(property "Datasheet" "https://www.murata.com/products/productdetail?partno=GRM155R61H104KE14%23"
			(at 300.99 31.75 0)
			(effects
				(font
					(size 1.27 1.27)
					(thickness 0.15)
				)
				(justify left bottom)
				(hide yes)
			)
		)
		(property "Description" ""
			(at 285.75 52.07 0)
			(effects
				(font
					(size 1.27 1.27)
				)
			)
		)
		(property "Manufacturer" "Murata"
			(at 306.07 31.75 0)
			(effects
				(font
					(size 1.27 1.27)
					(thickness 0.15)
				)
				(justify left bottom)
				(hide yes)
			)
		)
		(property "MPN" "GRM155R61H104KE14D"
			(at 303.53 31.75 0)
			(effects
				(font
					(size 1.27 1.27)
					(thickness 0.15)
				)
				(justify left bottom)
				(hide yes)
			)
		)
		(property "Val" "100n"
			(at 286.385 51.435 90)
			(effects
				(font
					(size 1.27 1.27)
					(thickness 0.15)
				)
				(justify right)
			)
		)
		(property "License" "Apache-2.0"
			(at 308.61 31.75 0)
			(effects
				(font
					(size 1.27 1.27)
					(thickness 0.15)
				)
				(justify left bottom)
				(hide yes)
			)
		)
		(property "Author" "Antmicro"
			(at 311.15 31.75 0)
			(effects
				(font
					(size 1.27 1.27)
					(thickness 0.15)
				)
				(justify left bottom)
				(hide yes)
			)
		)
		(property "Voltage" "50V"
			(at 313.69 31.75 0)
			(effects
				(font
					(size 1.27 1.27)
				)
				(justify left bottom)
				(hide yes)
			)
		)
		(property "Dielectric" "X5R"
			(at 316.23 31.75 0)
			(effects
				(font
					(size 1.27 1.27)
				)
				(justify left bottom)
				(hide yes)
			)
		)
		(pin "1"
		)
		(pin "2"
		)
		(instances
			(project "k410t-devboard"
				(path ""
					(reference "C96")
					(unit 1)
				)
			)
		)
	)
	(symbol
		(lib_id "antmicroCapacitors0402:C_100n_0402")
		(at 270.51 182.88 90)
		(unit 1)
		(exclude_from_sim no)
		(in_bom yes)
		(on_board yes)
		(dnp no)
		(property "Reference" "C375"
			(at 271.145 178.435 90)
			(effects
				(font
					(size 1.27 1.27)
				)
				(justify right)
			)
		)
		(property "Value" "C_100n_0402"
			(at 280.67 162.56 0)
			(effects
				(font
					(size 1.27 1.27)
					(thickness 0.15)
				)
				(justify left bottom)
				(hide yes)
			)
		)
		(property "Footprint" "antmicro-footprints:C_0402_1005Metric"
			(at 283.21 162.56 0)
			(effects
				(font
					(size 1.27 1.27)
					(thickness 0.15)
				)
				(justify left bottom)
				(hide yes)
			)
		)
		(property "Datasheet" "https://www.murata.com/products/productdetail?partno=GRM155R61H104KE14%23"
			(at 285.75 162.56 0)
			(effects
				(font
					(size 1.27 1.27)
					(thickness 0.15)
				)
				(justify left bottom)
				(hide yes)
			)
		)
		(property "Description" ""
			(at 270.51 182.88 0)
			(effects
				(font
					(size 1.27 1.27)
				)
			)
		)
		(property "Manufacturer" "Murata"
			(at 290.83 162.56 0)
			(effects
				(font
					(size 1.27 1.27)
					(thickness 0.15)
				)
				(justify left bottom)
				(hide yes)
			)
		)
		(property "MPN" "GRM155R61H104KE14D"
			(at 288.29 162.56 0)
			(effects
				(font
					(size 1.27 1.27)
					(thickness 0.15)
				)
				(justify left bottom)
				(hide yes)
			)
		)
		(property "Val" "100n"
			(at 271.145 182.245 90)
			(effects
				(font
					(size 1.27 1.27)
					(thickness 0.15)
				)
				(justify right)
			)
		)
		(property "License" "Apache-2.0"
			(at 293.37 162.56 0)
			(effects
				(font
					(size 1.27 1.27)
					(thickness 0.15)
				)
				(justify left bottom)
				(hide yes)
			)
		)
		(property "Author" "Antmicro"
			(at 295.91 162.56 0)
			(effects
				(font
					(size 1.27 1.27)
					(thickness 0.15)
				)
				(justify left bottom)
				(hide yes)
			)
		)
		(property "Voltage" "50V"
			(at 298.45 162.56 0)
			(effects
				(font
					(size 1.27 1.27)
				)
				(justify left bottom)
				(hide yes)
			)
		)
		(property "Dielectric" "X5R"
			(at 300.99 162.56 0)
			(effects
				(font
					(size 1.27 1.27)
				)
				(justify left bottom)
				(hide yes)
			)
		)
		(pin "1"
		)
		(pin "2"
		)
		(instances
			(project "k410t-devboard"
				(path ""
					(reference "C375")
					(unit 1)
				)
			)
		)
	)
	(symbol
		(lib_id "antmicroCapacitors0402:C_100n_0402")
		(at 247.65 52.07 90)
		(unit 1)
		(exclude_from_sim no)
		(in_bom yes)
		(on_board yes)
		(dnp no)
		(property "Reference" "C62"
			(at 248.285 47.625 90)
			(effects
				(font
					(size 1.27 1.27)
				)
				(justify right)
			)
		)
		(property "Value" "C_100n_0402"
			(at 257.81 31.75 0)
			(effects
				(font
					(size 1.27 1.27)
					(thickness 0.15)
				)
				(justify left bottom)
				(hide yes)
			)
		)
		(property "Footprint" "antmicro-footprints:C_0402_1005Metric"
			(at 260.35 31.75 0)
			(effects
				(font
					(size 1.27 1.27)
					(thickness 0.15)
				)
				(justify left bottom)
				(hide yes)
			)
		)
		(property "Datasheet" "https://www.murata.com/products/productdetail?partno=GRM155R61H104KE14%23"
			(at 262.89 31.75 0)
			(effects
				(font
					(size 1.27 1.27)
					(thickness 0.15)
				)
				(justify left bottom)
				(hide yes)
			)
		)
		(property "Description" ""
			(at 247.65 52.07 0)
			(effects
				(font
					(size 1.27 1.27)
				)
			)
		)
		(property "Manufacturer" "Murata"
			(at 267.97 31.75 0)
			(effects
				(font
					(size 1.27 1.27)
					(thickness 0.15)
				)
				(justify left bottom)
				(hide yes)
			)
		)
		(property "MPN" "GRM155R61H104KE14D"
			(at 265.43 31.75 0)
			(effects
				(font
					(size 1.27 1.27)
					(thickness 0.15)
				)
				(justify left bottom)
				(hide yes)
			)
		)
		(property "Val" "100n"
			(at 248.285 51.435 90)
			(effects
				(font
					(size 1.27 1.27)
					(thickness 0.15)
				)
				(justify right)
			)
		)
		(property "License" "Apache-2.0"
			(at 270.51 31.75 0)
			(effects
				(font
					(size 1.27 1.27)
					(thickness 0.15)
				)
				(justify left bottom)
				(hide yes)
			)
		)
		(property "Author" "Antmicro"
			(at 273.05 31.75 0)
			(effects
				(font
					(size 1.27 1.27)
					(thickness 0.15)
				)
				(justify left bottom)
				(hide yes)
			)
		)
		(property "Voltage" "50V"
			(at 275.59 31.75 0)
			(effects
				(font
					(size 1.27 1.27)
				)
				(justify left bottom)
				(hide yes)
			)
		)
		(property "Dielectric" "X5R"
			(at 278.13 31.75 0)
			(effects
				(font
					(size 1.27 1.27)
				)
				(justify left bottom)
				(hide yes)
			)
		)
		(pin "1"
		)
		(pin "2"
		)
		(instances
			(project "k410t-devboard"
				(path ""
					(reference "C62")
					(unit 1)
				)
			)
		)
	)
	(symbol
		(lib_id "antmicropower:GND")
		(at 300.99 55.88 0)
		(mirror y)
		(unit 1)
		(exclude_from_sim no)
		(in_bom yes)
		(on_board yes)
		(dnp no)
		(property "Reference" "#PWR030"
			(at 300.99 62.23 0)
			(effects
				(font
					(size 1.27 1.27)
				)
				(hide yes)
			)
		)
		(property "Value" "GND"
			(at 300.99 59.69 0)
			(effects
				(font
					(size 1.27 1.27)
				)
			)
		)
		(property "Footprint" ""
			(at 292.1 63.5 0)
			(effects
				(font
					(size 1.27 1.27)
					(thickness 0.15)
				)
				(justify left bottom)
				(hide yes)
			)
		)
		(property "Datasheet" ""
			(at 292.1 68.58 0)
			(effects
				(font
					(size 1.27 1.27)
					(thickness 0.15)
				)
				(justify left bottom)
				(hide yes)
			)
		)
		(property "Description" ""
			(at 300.99 55.88 0)
			(effects
				(font
					(size 1.27 1.27)
				)
			)
		)
		(property "Author" "Antmicro"
			(at 292.1 63.5 0)
			(effects
				(font
					(size 1.27 1.27)
					(thickness 0.15)
				)
				(justify left bottom)
				(hide yes)
			)
		)
		(property "License" "Apache-2.0"
			(at 292.1 66.04 0)
			(effects
				(font
					(size 1.27 1.27)
					(thickness 0.15)
				)
				(justify left bottom)
				(hide yes)
			)
		)
		(pin "1"
		)
		(instances
			(project "k410t-devboard"
				(path ""
					(reference "#PWR030")
					(unit 1)
				)
			)
		)
	)
	(symbol
		(lib_id "antmicroCapacitors0402:C_100n_0402")
		(at 278.13 52.07 90)
		(unit 1)
		(exclude_from_sim no)
		(in_bom yes)
		(on_board yes)
		(dnp no)
		(property "Reference" "C91"
			(at 278.765 47.625 90)
			(effects
				(font
					(size 1.27 1.27)
				)
				(justify right)
			)
		)
		(property "Value" "C_100n_0402"
			(at 288.29 31.75 0)
			(effects
				(font
					(size 1.27 1.27)
					(thickness 0.15)
				)
				(justify left bottom)
				(hide yes)
			)
		)
		(property "Footprint" "antmicro-footprints:C_0402_1005Metric"
			(at 290.83 31.75 0)
			(effects
				(font
					(size 1.27 1.27)
					(thickness 0.15)
				)
				(justify left bottom)
				(hide yes)
			)
		)
		(property "Datasheet" "https://www.murata.com/products/productdetail?partno=GRM155R61H104KE14%23"
			(at 293.37 31.75 0)
			(effects
				(font
					(size 1.27 1.27)
					(thickness 0.15)
				)
				(justify left bottom)
				(hide yes)
			)
		)
		(property "Description" ""
			(at 278.13 52.07 0)
			(effects
				(font
					(size 1.27 1.27)
				)
			)
		)
		(property "Manufacturer" "Murata"
			(at 298.45 31.75 0)
			(effects
				(font
					(size 1.27 1.27)
					(thickness 0.15)
				)
				(justify left bottom)
				(hide yes)
			)
		)
		(property "MPN" "GRM155R61H104KE14D"
			(at 295.91 31.75 0)
			(effects
				(font
					(size 1.27 1.27)
					(thickness 0.15)
				)
				(justify left bottom)
				(hide yes)
			)
		)
		(property "Val" "100n"
			(at 278.765 51.435 90)
			(effects
				(font
					(size 1.27 1.27)
					(thickness 0.15)
				)
				(justify right)
			)
		)
		(property "License" "Apache-2.0"
			(at 300.99 31.75 0)
			(effects
				(font
					(size 1.27 1.27)
					(thickness 0.15)
				)
				(justify left bottom)
				(hide yes)
			)
		)
		(property "Author" "Antmicro"
			(at 303.53 31.75 0)
			(effects
				(font
					(size 1.27 1.27)
					(thickness 0.15)
				)
				(justify left bottom)
				(hide yes)
			)
		)
		(property "Voltage" "50V"
			(at 306.07 31.75 0)
			(effects
				(font
					(size 1.27 1.27)
				)
				(justify left bottom)
				(hide yes)
			)
		)
		(property "Dielectric" "X5R"
			(at 308.61 31.75 0)
			(effects
				(font
					(size 1.27 1.27)
				)
				(justify left bottom)
				(hide yes)
			)
		)
		(pin "1"
		)
		(pin "2"
		)
		(instances
			(project "k410t-devboard"
				(path ""
					(reference "C91")
					(unit 1)
				)
			)
		)
	)
	(symbol
		(lib_id "antmicroCapacitors0402:C_100n_0402")
		(at 293.37 52.07 90)
		(unit 1)
		(exclude_from_sim no)
		(in_bom yes)
		(on_board yes)
		(dnp no)
		(property "Reference" "C102"
			(at 294.005 47.625 90)
			(effects
				(font
					(size 1.27 1.27)
				)
				(justify right)
			)
		)
		(property "Value" "C_100n_0402"
			(at 303.53 31.75 0)
			(effects
				(font
					(size 1.27 1.27)
					(thickness 0.15)
				)
				(justify left bottom)
				(hide yes)
			)
		)
		(property "Footprint" "antmicro-footprints:C_0402_1005Metric"
			(at 306.07 31.75 0)
			(effects
				(font
					(size 1.27 1.27)
					(thickness 0.15)
				)
				(justify left bottom)
				(hide yes)
			)
		)
		(property "Datasheet" "https://www.murata.com/products/productdetail?partno=GRM155R61H104KE14%23"
			(at 308.61 31.75 0)
			(effects
				(font
					(size 1.27 1.27)
					(thickness 0.15)
				)
				(justify left bottom)
				(hide yes)
			)
		)
		(property "Description" ""
			(at 293.37 52.07 0)
			(effects
				(font
					(size 1.27 1.27)
				)
			)
		)
		(property "Manufacturer" "Murata"
			(at 313.69 31.75 0)
			(effects
				(font
					(size 1.27 1.27)
					(thickness 0.15)
				)
				(justify left bottom)
				(hide yes)
			)
		)
		(property "MPN" "GRM155R61H104KE14D"
			(at 311.15 31.75 0)
			(effects
				(font
					(size 1.27 1.27)
					(thickness 0.15)
				)
				(justify left bottom)
				(hide yes)
			)
		)
		(property "Val" "100n"
			(at 294.005 51.435 90)
			(effects
				(font
					(size 1.27 1.27)
					(thickness 0.15)
				)
				(justify right)
			)
		)
		(property "License" "Apache-2.0"
			(at 316.23 31.75 0)
			(effects
				(font
					(size 1.27 1.27)
					(thickness 0.15)
				)
				(justify left bottom)
				(hide yes)
			)
		)
		(property "Author" "Antmicro"
			(at 318.77 31.75 0)
			(effects
				(font
					(size 1.27 1.27)
					(thickness 0.15)
				)
				(justify left bottom)
				(hide yes)
			)
		)
		(property "Voltage" "50V"
			(at 321.31 31.75 0)
			(effects
				(font
					(size 1.27 1.27)
				)
				(justify left bottom)
				(hide yes)
			)
		)
		(property "Dielectric" "X5R"
			(at 323.85 31.75 0)
			(effects
				(font
					(size 1.27 1.27)
				)
				(justify left bottom)
				(hide yes)
			)
		)
		(pin "1"
		)
		(pin "2"
		)
		(instances
			(project "k410t-devboard"
				(path ""
					(reference "C102")
					(unit 1)
				)
			)
		)
	)
	(symbol
		(lib_id "antmicropower:+1V35")
		(at 255.27 210.82 0)
		(unit 1)
		(exclude_from_sim no)
		(in_bom yes)
		(on_board yes)
		(dnp no)
		(fields_autoplaced yes)
		(property "Reference" "#PWR032"
			(at 255.27 214.63 0)
			(effects
				(font
					(size 1.27 1.27)
				)
				(hide yes)
			)
		)
		(property "Value" "+1V35"
			(at 255.27 207.264 0)
			(effects
				(font
					(size 1.27 1.27)
				)
			)
		)
		(property "Footprint" ""
			(at 255.27 210.82 0)
			(effects
				(font
					(size 1.27 1.27)
				)
				(hide yes)
			)
		)
		(property "Datasheet" ""
			(at 255.27 210.82 0)
			(effects
				(font
					(size 1.27 1.27)
				)
				(hide yes)
			)
		)
		(property "Description" ""
			(at 255.27 210.82 0)
			(effects
				(font
					(size 1.27 1.27)
				)
			)
		)
		(pin "1"
		)
		(instances
			(project "k410t-devboard"
				(path ""
					(reference "#PWR032")
					(unit 1)
				)
			)
		)
	)
	(symbol
		(lib_id "antmicroResistors0402:R_80R6_0402_EIA")
		(at 255.27 218.44 90)
		(unit 1)
		(exclude_from_sim no)
		(in_bom yes)
		(on_board yes)
		(dnp no)
		(property "Reference" "R340"
			(at 256.54 214.63 90)
			(effects
				(font
					(size 1.27 1.27)
				)
				(justify right)
			)
		)
		(property "Value" "R_80R6_0402_EIA"
			(at 267.97 198.12 0)
			(effects
				(font
					(size 1.27 1.27)
					(thickness 0.15)
				)
				(justify left bottom)
				(hide yes)
			)
		)
		(property "Footprint" "antmicro-footprints:R_0402_1005Metric_EIA"
			(at 270.51 198.12 0)
			(effects
				(font
					(size 1.27 1.27)
					(thickness 0.15)
				)
				(justify left bottom)
				(hide yes)
			)
		)
		(property "Datasheet" "https://www.bourns.com/docs/product-datasheets/cr.pdf"
			(at 273.05 198.12 0)
			(effects
				(font
					(size 1.27 1.27)
					(thickness 0.15)
				)
				(justify left bottom)
				(hide yes)
			)
		)
		(property "Description" ""
			(at 255.27 218.44 0)
			(effects
				(font
					(size 1.27 1.27)
				)
			)
		)
		(property "Manufacturer" "Multicomp Pro"
			(at 278.13 198.12 0)
			(effects
				(font
					(size 1.27 1.27)
					(thickness 0.15)
				)
				(justify left bottom)
				(hide yes)
			)
		)
		(property "MPN" "MC00625W0402180R6"
			(at 275.59 198.12 0)
			(effects
				(font
					(size 1.27 1.27)
					(thickness 0.15)
				)
				(justify left bottom)
				(hide yes)
			)
		)
		(property "Val" "80R6"
			(at 256.54 217.17 90)
			(effects
				(font
					(size 1.27 1.27)
					(thickness 0.15)
				)
				(justify right)
			)
		)
		(property "License" "Apache-2.0"
			(at 280.67 198.12 0)
			(effects
				(font
					(size 1.27 1.27)
					(thickness 0.15)
				)
				(justify left bottom)
				(hide yes)
			)
		)
		(property "Author" "Antmicro"
			(at 283.21 198.12 0)
			(effects
				(font
					(size 1.27 1.27)
					(thickness 0.15)
				)
				(justify left bottom)
				(hide yes)
			)
		)
		(property "Tolerance" "1%"
			(at 265.43 198.12 0)
			(effects
				(font
					(size 1.27 1.27)
				)
				(justify left bottom)
				(hide yes)
			)
		)
		(pin "1"
		)
		(pin "2"
		)
		(instances
			(project "k410t-devboard"
				(path ""
					(reference "R340")
					(unit 1)
				)
			)
		)
	)
	(symbol
		(lib_name "XC7K410T-2FFG900I_1")
		(lib_id "antmicroFPGAChips:XC7K410T-2FFG900I")
		(at 187.96 74.93 0)
		(unit 5)
		(exclude_from_sim no)
		(in_bom yes)
		(on_board yes)
		(dnp no)
		(fields_autoplaced yes)
		(property "Reference" "U1"
			(at 215.265 64.77 0)
			(effects
				(font
					(size 1.27 1.27)
					(thickness 0.15)
				)
			)
		)
		(property "Value" "XC7K410T-2FFG900I"
			(at 215.265 67.31 0)
			(effects
				(font
					(size 1.27 1.27)
					(thickness 0.15)
				)
			)
		)
		(property "Footprint" "antmicro-footprints:BGA-900_31x31mm_Layout30x30_P1x1mm_FFG900"
			(at 187.96 48.26 0)
			(effects
				(font
					(size 1.27 1.27)
					(thickness 0.15)
				)
				(justify left bottom)
				(hide yes)
			)
		)
		(property "Datasheet" "https://eu.mouser.com/datasheet/2/903/ds180_7Series_Overview-1591537.pdf"
			(at 187.96 50.8 0)
			(effects
				(font
					(size 1.27 1.27)
					(thickness 0.15)
				)
				(justify left bottom)
				(hide yes)
			)
		)
		(property "Description" ""
			(at 187.96 74.93 0)
			(effects
				(font
					(size 1.27 1.27)
				)
			)
		)
		(property "Manufacturer" "AMD-Xilinx"
			(at 187.96 53.34 0)
			(effects
				(font
					(size 1.27 1.27)
					(thickness 0.15)
				)
				(justify left bottom)
				(hide yes)
			)
		)
		(property "MPN" "XC7K410T-2FFG900I"
			(at 187.96 55.88 0)
			(effects
				(font
					(size 1.27 1.27)
					(thickness 0.15)
				)
				(justify left bottom)
				(hide yes)
			)
		)
		(property "Author" "Antmicro"
			(at 187.96 58.42 0)
			(effects
				(font
					(size 1.27 1.27)
					(thickness 0.15)
				)
				(justify left bottom)
				(hide yes)
			)
		)
		(property "License" "Apache-2.0"
			(at 187.96 60.96 0)
			(effects
				(font
					(size 1.27 1.27)
					(thickness 0.15)
				)
				(justify left bottom)
				(hide yes)
			)
		)
		(pin "AA10"
		)
		(pin "AA11"
		)
		(pin "AA12"
		)
		(pin "AA13"
		)
		(pin "AA8"
		)
		(pin "AB10"
		)
		(pin "AB12"
		)
		(pin "AB13"
		)
		(pin "AB8"
		)
		(pin "AB9"
		)
		(pin "AC10"
		)
		(pin "AC11"
		)
		(pin "AC12"
		)
		(pin "AC9"
		)
		(pin "AD11"
		)
		(pin "AD12"
		)
		(pin "AD13"
		)
		(pin "AD8"
		)
		(pin "AD9"
		)
		(pin "AE10"
		)
		(pin "AE11"
		)
		(pin "AE13"
		)
		(pin "AE8"
		)
		(pin "AE9"
		)
		(pin "AF10"
		)
		(pin "AF11"
		)
		(pin "AF12"
		)
		(pin "AF13"
		)
		(pin "AG10"
		)
		(pin "AG12"
		)
		(pin "AG13"
		)
		(pin "AG9"
		)
		(pin "AH10"
		)
		(pin "AH11"
		)
		(pin "AH12"
		)
		(pin "AH14"
		)
		(pin "AH9"
		)
		(pin "AJ11"
		)
		(pin "AJ12"
		)
		(pin "AJ13"
		)
		(pin "AJ14"
		)
		(pin "AJ9"
		)
		(pin "AK10"
		)
		(pin "AK11"
		)
		(pin "AK13"
		)
		(pin "AK14"
		)
		(pin "AK9"
		)
		(pin "Y10"
		)
		(pin "Y11"
		)
		(pin "Y13"
		)
		(pin "AA22"
		)
		(pin "AA23"
		)
		(pin "AB20"
		)
		(pin "AB22"
		)
		(pin "AB23"
		)
		(pin "AB24"
		)
		(pin "AC20"
		)
		(pin "AC21"
		)
		(pin "AC22"
		)
		(pin "AC24"
		)
		(pin "AC25"
		)
		(pin "AD21"
		)
		(pin "AD22"
		)
		(pin "AD23"
		)
		(pin "AD24"
		)
		(pin "AE20"
		)
		(pin "AE21"
		)
		(pin "AE23"
		)
		(pin "AE24"
		)
		(pin "AE25"
		)
		(pin "AF20"
		)
		(pin "AF21"
		)
		(pin "AF22"
		)
		(pin "AF23"
		)
		(pin "AF25"
		)
		(pin "AG20"
		)
		(pin "AG22"
		)
		(pin "AG23"
		)
		(pin "AG24"
		)
		(pin "AG25"
		)
		(pin "AH20"
		)
		(pin "AH21"
		)
		(pin "AH22"
		)
		(pin "AH24"
		)
		(pin "AH25"
		)
		(pin "AJ21"
		)
		(pin "AJ22"
		)
		(pin "AJ23"
		)
		(pin "AJ24"
		)
		(pin "AK20"
		)
		(pin "AK21"
		)
		(pin "AK23"
		)
		(pin "AK24"
		)
		(pin "AK25"
		)
		(pin "Y20"
		)
		(pin "Y21"
		)
		(pin "Y23"
		)
		(pin "Y24"
		)
		(pin "P24"
		)
		(pin "P26"
		)
		(pin "P27"
		)
		(pin "P28"
		)
		(pin "P29"
		)
		(pin "R19"
		)
		(pin "R20"
		)
		(pin "R21"
		)
		(pin "R23"
		)
		(pin "R24"
		)
		(pin "R25"
		)
		(pin "R26"
		)
		(pin "R28"
		)
		(pin "R29"
		)
		(pin "R30"
		)
		(pin "T20"
		)
		(pin "T21"
		)
		(pin "T22"
		)
		(pin "T23"
		)
		(pin "T25"
		)
		(pin "T26"
		)
		(pin "T27"
		)
		(pin "T28"
		)
		(pin "T30"
		)
		(pin "U19"
		)
		(pin "U20"
		)
		(pin "U22"
		)
		(pin "U23"
		)
		(pin "U24"
		)
		(pin "U25"
		)
		(pin "U27"
		)
		(pin "U28"
		)
		(pin "U29"
		)
		(pin "U30"
		)
		(pin "V19"
		)
		(pin "V20"
		)
		(pin "V21"
		)
		(pin "V22"
		)
		(pin "V24"
		)
		(pin "V25"
		)
		(pin "V26"
		)
		(pin "V27"
		)
		(pin "V29"
		)
		(pin "V30"
		)
		(pin "W19"
		)
		(pin "W21"
		)
		(pin "W22"
		)
		(pin "W23"
		)
		(pin "W24"
		)
		(pin "W26"
		)
		(pin "A23"
		)
		(pin "A25"
		)
		(pin "A26"
		)
		(pin "A27"
		)
		(pin "A28"
		)
		(pin "A30"
		)
		(pin "B23"
		)
		(pin "B24"
		)
		(pin "B25"
		)
		(pin "B27"
		)
		(pin "B28"
		)
		(pin "B29"
		)
		(pin "B30"
		)
		(pin "C24"
		)
		(pin "C25"
		)
		(pin "C26"
		)
		(pin "C27"
		)
		(pin "C29"
		)
		(pin "C30"
		)
		(pin "D23"
		)
		(pin "D24"
		)
		(pin "D26"
		)
		(pin "D27"
		)
		(pin "D28"
		)
		(pin "D29"
		)
		(pin "E23"
		)
		(pin "E24"
		)
		(pin "E25"
		)
		(pin "E26"
		)
		(pin "B2"
		)
		(pin "B5"
		)
		(pin "B6"
		)
		(pin "C3"
		)
		(pin "C4"
		)
		(pin "E30"
		)
		(pin "F23"
		)
		(pin "F25"
		)
		(pin "F26"
		)
		(pin "F27"
		)
		(pin "F28"
		)
		(pin "F30"
		)
		(pin "G23"
		)
		(pin "G24"
		)
		(pin "G25"
		)
		(pin "G27"
		)
		(pin "G28"
		)
		(pin "G29"
		)
		(pin "G30"
		)
		(pin "H24"
		)
		(pin "H25"
		)
		(pin "H26"
		)
		(pin "H27"
		)
		(pin "H30"
		)
		(pin "A11"
		)
		(pin "A12"
		)
		(pin "A13"
		)
		(pin "A15"
		)
		(pin "B12"
		)
		(pin "B13"
		)
		(pin "B14"
		)
		(pin "B15"
		)
		(pin "C11"
		)
		(pin "C12"
		)
		(pin "C14"
		)
		(pin "C15"
		)
		(pin "D11"
		)
		(pin "D12"
		)
		(pin "D13"
		)
		(pin "D14"
		)
		(pin "E11"
		)
		(pin "E13"
		)
		(pin "E14"
		)
		(pin "E15"
		)
		(pin "E16"
		)
		(pin "F11"
		)
		(pin "F12"
		)
		(pin "F13"
		)
		(pin "F15"
		)
		(pin "F16"
		)
		(pin "G12"
		)
		(pin "G13"
		)
		(pin "G14"
		)
		(pin "G15"
		)
		(pin "H11"
		)
		(pin "H12"
		)
		(pin "H14"
		)
		(pin "H15"
		)
		(pin "H16"
		)
		(pin "J11"
		)
		(pin "J12"
		)
		(pin "J13"
		)
		(pin "J14"
		)
		(pin "J16"
		)
		(pin "K11"
		)
		(pin "K13"
		)
		(pin "K14"
		)
		(pin "K15"
		)
		(pin "K16"
		)
		(pin "L11"
		)
		(pin "L12"
		)
		(pin "L13"
		)
		(pin "L15"
		)
		(pin "L16"
		)
		(pin "A3"
		)
		(pin "A4"
		)
		(pin "A7"
		)
		(pin "A8"
		)
		(pin "AA3"
		)
		(pin "AA4"
		)
		(pin "B1"
		)
		(pin "G16"
		)
		(pin "G2"
		)
		(pin "G26"
		)
		(pin "G6"
		)
		(pin "G9"
		)
		(pin "H13"
		)
		(pin "H23"
		)
		(pin "H4"
		)
		(pin "H8"
		)
		(pin "H9"
		)
		(pin "J1"
		)
		(pin "J10"
		)
		(pin "C7"
		)
		(pin "C8"
		)
		(pin "D1"
		)
		(pin "D2"
		)
		(pin "D5"
		)
		(pin "D6"
		)
		(pin "E3"
		)
		(pin "E4"
		)
		(pin "E7"
		)
		(pin "E8"
		)
		(pin "F1"
		)
		(pin "F2"
		)
		(pin "F5"
		)
		(pin "F6"
		)
		(pin "G3"
		)
		(pin "G4"
		)
		(pin "G7"
		)
		(pin "G8"
		)
		(pin "H1"
		)
		(pin "H2"
		)
		(pin "H5"
		)
		(pin "H6"
		)
		(pin "J3"
		)
		(pin "J4"
		)
		(pin "J7"
		)
		(pin "J8"
		)
		(pin "K1"
		)
		(pin "K2"
		)
		(pin "K5"
		)
		(pin "K6"
		)
		(pin "L3"
		)
		(pin "L4"
		)
		(pin "L7"
		)
		(pin "L8"
		)
		(pin "M1"
		)
		(pin "M2"
		)
		(pin "M5"
		)
		(pin "M6"
		)
		(pin "N3"
		)
		(pin "N4"
		)
		(pin "N7"
		)
		(pin "N8"
		)
		(pin "P1"
		)
		(pin "P2"
		)
		(pin "P5"
		)
		(pin "P6"
		)
		(pin "R3"
		)
		(pin "R4"
		)
		(pin "R7"
		)
		(pin "R8"
		)
		(pin "T1"
		)
		(pin "T2"
		)
		(pin "T5"
		)
		(pin "T6"
		)
		(pin "U3"
		)
		(pin "U4"
		)
		(pin "U7"
		)
		(pin "U8"
		)
		(pin "V1"
		)
		(pin "V2"
		)
		(pin "V5"
		)
		(pin "V6"
		)
		(pin "W3"
		)
		(pin "W4"
		)
		(pin "Y1"
		)
		(pin "Y2"
		)
		(pin "Y5"
		)
		(pin "Y6"
		)
		(pin "B3"
		)
		(pin "B7"
		)
		(pin "C5"
		)
		(pin "D3"
		)
		(pin "D7"
		)
		(pin "E5"
		)
		(pin "F3"
		)
		(pin "F7"
		)
		(pin "G5"
		)
		(pin "H3"
		)
		(pin "H7"
		)
		(pin "J5"
		)
		(pin "K3"
		)
		(pin "K7"
		)
		(pin "L5"
		)
		(pin "M3"
		)
		(pin "M7"
		)
		(pin "N5"
		)
		(pin "P3"
		)
		(pin "P7"
		)
		(pin "R5"
		)
		(pin "T3"
		)
		(pin "T7"
		)
		(pin "U5"
		)
		(pin "V3"
		)
		(pin "V7"
		)
		(pin "W5"
		)
		(pin "W7"
		)
		(pin "W8"
		)
		(pin "A10"
		)
		(pin "AB1"
		)
		(pin "AB2"
		)
		(pin "AB5"
		)
		(pin "B10"
		)
		(pin "E10"
		)
		(pin "F10"
		)
		(pin "G10"
		)
		(pin "H10"
		)
		(pin "K10"
		)
		(pin "L10"
		)
		(pin "M10"
		)
		(pin "R14"
		)
		(pin "R15"
		)
		(pin "T14"
		)
		(pin "T15"
		)
		(pin "U14"
		)
		(pin "U15"
		)
		(pin "A19"
		)
		(pin "A29"
		)
		(pin "AA19"
		)
		(pin "AA29"
		)
		(pin "AA9"
		)
		(pin "AB16"
		)
		(pin "AB26"
		)
		(pin "AB6"
		)
		(pin "AC13"
		)
		(pin "AC23"
		)
		(pin "AC3"
		)
		(pin "AD10"
		)
		(pin "AD20"
		)
		(pin "AD30"
		)
		(pin "AE17"
		)
		(pin "AE27"
		)
		(pin "AE7"
		)
		(pin "AF14"
		)
		(pin "AF24"
		)
		(pin "AF4"
		)
		(pin "AG1"
		)
		(pin "AG11"
		)
		(pin "AG21"
		)
		(pin "AH18"
		)
		(pin "AH28"
		)
		(pin "AH8"
		)
		(pin "AJ15"
		)
		(pin "AJ25"
		)
		(pin "AJ5"
		)
		(pin "AK12"
		)
		(pin "AK2"
		)
		(pin "AK22"
		)
		(pin "B16"
		)
		(pin "B26"
		)
		(pin "C13"
		)
		(pin "C23"
		)
		(pin "D10"
		)
		(pin "D20"
		)
		(pin "D30"
		)
		(pin "E17"
		)
		(pin "E27"
		)
		(pin "F14"
		)
		(pin "F24"
		)
		(pin "G11"
		)
		(pin "G21"
		)
		(pin "H18"
		)
		(pin "H28"
		)
		(pin "J15"
		)
		(pin "J25"
		)
		(pin "K12"
		)
		(pin "K22"
		)
		(pin "L19"
		)
		(pin "L29"
		)
		(pin "M26"
		)
		(pin "N23"
		)
		(pin "P20"
		)
		(pin "P30"
		)
		(pin "R27"
		)
		(pin "T24"
		)
		(pin "T9"
		)
		(pin "U21"
		)
		(pin "V28"
		)
		(pin "W25"
		)
		(pin "Y12"
		)
		(pin "Y22"
		)
		(pin "A1"
		)
		(pin "A14"
		)
		(pin "A2"
		)
		(pin "A24"
		)
		(pin "A5"
		)
		(pin "A6"
		)
		(pin "A9"
		)
		(pin "AA1"
		)
		(pin "AA14"
		)
		(pin "AA2"
		)
		(pin "AA24"
		)
		(pin "AA5"
		)
		(pin "AA6"
		)
		(pin "AA7"
		)
		(pin "AB11"
		)
		(pin "AB21"
		)
		(pin "AB3"
		)
		(pin "AB4"
		)
		(pin "AC18"
		)
		(pin "AC28"
		)
		(pin "AC8"
		)
		(pin "AD15"
		)
		(pin "AD25"
		)
		(pin "AD5"
		)
		(pin "AE12"
		)
		(pin "AE2"
		)
		(pin "AE22"
		)
		(pin "AF19"
		)
		(pin "AF29"
		)
		(pin "AF9"
		)
		(pin "AG16"
		)
		(pin "AG26"
		)
		(pin "AG6"
		)
		(pin "AH13"
		)
		(pin "AH23"
		)
		(pin "AH3"
		)
		(pin "AJ10"
		)
		(pin "AJ20"
		)
		(pin "AJ30"
		)
		(pin "AK17"
		)
		(pin "AK27"
		)
		(pin "AK7"
		)
		(pin "B11"
		)
		(pin "B21"
		)
		(pin "B4"
		)
		(pin "B8"
		)
		(pin "B9"
		)
		(pin "C1"
		)
		(pin "C10"
		)
		(pin "C18"
		)
		(pin "C2"
		)
		(pin "C28"
		)
		(pin "C6"
		)
		(pin "C9"
		)
		(pin "D15"
		)
		(pin "D25"
		)
		(pin "D4"
		)
		(pin "D8"
		)
		(pin "D9"
		)
		(pin "E1"
		)
		(pin "E12"
		)
		(pin "E2"
		)
		(pin "E22"
		)
		(pin "E6"
		)
		(pin "E9"
		)
		(pin "F19"
		)
		(pin "F29"
		)
		(pin "F4"
		)
		(pin "F8"
		)
		(pin "F9"
		)
		(pin "G1"
		)
		(pin "J2"
		)
		(pin "J20"
		)
		(pin "J30"
		)
		(pin "J6"
		)
		(pin "J9"
		)
		(pin "K17"
		)
		(pin "K27"
		)
		(pin "K4"
		)
		(pin "K8"
		)
		(pin "K9"
		)
		(pin "L1"
		)
		(pin "L14"
		)
		(pin "L2"
		)
		(pin "L24"
		)
		(pin "L6"
		)
		(pin "L9"
		)
		(pin "M11"
		)
		(pin "M12"
		)
		(pin "M13"
		)
		(pin "M14"
		)
		(pin "M15"
		)
		(pin "M16"
		)
		(pin "M17"
		)
		(pin "M18"
		)
		(pin "M21"
		)
		(pin "M4"
		)
		(pin "M8"
		)
		(pin "M9"
		)
		(pin "N1"
		)
		(pin "N10"
		)
		(pin "N11"
		)
		(pin "N12"
		)
		(pin "N13"
		)
		(pin "N14"
		)
		(pin "N15"
		)
		(pin "N16"
		)
		(pin "N17"
		)
		(pin "N18"
		)
		(pin "N2"
		)
		(pin "N28"
		)
		(pin "N6"
		)
		(pin "N9"
		)
		(pin "P10"
		)
		(pin "P11"
		)
		(pin "P12"
		)
		(pin "P13"
		)
		(pin "P14"
		)
		(pin "P15"
		)
		(pin "P16"
		)
		(pin "P17"
		)
		(pin "P18"
		)
		(pin "P25"
		)
		(pin "P4"
		)
		(pin "P8"
		)
		(pin "P9"
		)
		(pin "R1"
		)
		(pin "R10"
		)
		(pin "R11"
		)
		(pin "R12"
		)
		(pin "R13"
		)
		(pin "R16"
		)
		(pin "R17"
		)
		(pin "R18"
		)
		(pin "R2"
		)
		(pin "R22"
		)
		(pin "R6"
		)
		(pin "R9"
		)
		(pin "T10"
		)
		(pin "T11"
		)
		(pin "T12"
		)
		(pin "T13"
		)
		(pin "T16"
		)
		(pin "T17"
		)
		(pin "T18"
		)
		(pin "T19"
		)
		(pin "T29"
		)
		(pin "T4"
		)
		(pin "T8"
		)
		(pin "U1"
		)
		(pin "U10"
		)
		(pin "U11"
		)
		(pin "U12"
		)
		(pin "U13"
		)
		(pin "U16"
		)
		(pin "U17"
		)
		(pin "U18"
		)
		(pin "U2"
		)
		(pin "U26"
		)
		(pin "U6"
		)
		(pin "U9"
		)
		(pin "V10"
		)
		(pin "V11"
		)
		(pin "V12"
		)
		(pin "V13"
		)
		(pin "V14"
		)
		(pin "V15"
		)
		(pin "V16"
		)
		(pin "V17"
		)
		(pin "V18"
		)
		(pin "V23"
		)
		(pin "V4"
		)
		(pin "V8"
		)
		(pin "V9"
		)
		(pin "W1"
		)
		(pin "W10"
		)
		(pin "W11"
		)
		(pin "W12"
		)
		(pin "W13"
		)
		(pin "W14"
		)
		(pin "W15"
		)
		(pin "W16"
		)
		(pin "W17"
		)
		(pin "W18"
		)
		(pin "W2"
		)
		(pin "W20"
		)
		(pin "W30"
		)
		(pin "W6"
		)
		(pin "W9"
		)
		(pin "Y17"
		)
		(pin "Y27"
		)
		(pin "Y3"
		)
		(pin "Y4"
		)
		(pin "Y7"
		)
		(pin "Y8"
		)
		(pin "Y9"
		)
		(pin "AA25"
		)
		(pin "AA26"
		)
		(pin "AA27"
		)
		(pin "AA28"
		)
		(pin "AA30"
		)
		(pin "AB25"
		)
		(pin "AB27"
		)
		(pin "AB28"
		)
		(pin "AB29"
		)
		(pin "AB30"
		)
		(pin "AC26"
		)
		(pin "AC27"
		)
		(pin "AC29"
		)
		(pin "AC30"
		)
		(pin "AD26"
		)
		(pin "AD27"
		)
		(pin "AD28"
		)
		(pin "AD29"
		)
		(pin "AE26"
		)
		(pin "AE28"
		)
		(pin "AE29"
		)
		(pin "AE30"
		)
		(pin "AF26"
		)
		(pin "AF27"
		)
		(pin "AF28"
		)
		(pin "AF30"
		)
		(pin "AG27"
		)
		(pin "AG28"
		)
		(pin "AG29"
		)
		(pin "AG30"
		)
		(pin "AH26"
		)
		(pin "AH27"
		)
		(pin "AH29"
		)
		(pin "AH30"
		)
		(pin "AJ26"
		)
		(pin "AJ27"
		)
		(pin "AJ28"
		)
		(pin "AJ29"
		)
		(pin "AK26"
		)
		(pin "AK28"
		)
		(pin "AK29"
		)
		(pin "AK30"
		)
		(pin "W27"
		)
		(pin "W28"
		)
		(pin "W29"
		)
		(pin "Y25"
		)
		(pin "Y26"
		)
		(pin "Y28"
		)
		(pin "Y29"
		)
		(pin "Y30"
		)
		(pin "H29"
		)
		(pin "J21"
		)
		(pin "J22"
		)
		(pin "J23"
		)
		(pin "J24"
		)
		(pin "J26"
		)
		(pin "J27"
		)
		(pin "J28"
		)
		(pin "J29"
		)
		(pin "K21"
		)
		(pin "K23"
		)
		(pin "K24"
		)
		(pin "K25"
		)
		(pin "K26"
		)
		(pin "K28"
		)
		(pin "K29"
		)
		(pin "K30"
		)
		(pin "L20"
		)
		(pin "L21"
		)
		(pin "L22"
		)
		(pin "L23"
		)
		(pin "L25"
		)
		(pin "L26"
		)
		(pin "L27"
		)
		(pin "L28"
		)
		(pin "L30"
		)
		(pin "M19"
		)
		(pin "M20"
		)
		(pin "M22"
		)
		(pin "M23"
		)
		(pin "M24"
		)
		(pin "M25"
		)
		(pin "M27"
		)
		(pin "M28"
		)
		(pin "M29"
		)
		(pin "M30"
		)
		(pin "N19"
		)
		(pin "N20"
		)
		(pin "N21"
		)
		(pin "N22"
		)
		(pin "N24"
		)
		(pin "N25"
		)
		(pin "N26"
		)
		(pin "N27"
		)
		(pin "N29"
		)
		(pin "N30"
		)
		(pin "P19"
		)
		(pin "P21"
		)
		(pin "P22"
		)
		(pin "P23"
		)
		(pin "A16"
		)
		(pin "A17"
		)
		(pin "A18"
		)
		(pin "A20"
		)
		(pin "A21"
		)
		(pin "A22"
		)
		(pin "B17"
		)
		(pin "B18"
		)
		(pin "B19"
		)
		(pin "B20"
		)
		(pin "B22"
		)
		(pin "C16"
		)
		(pin "C17"
		)
		(pin "C19"
		)
		(pin "C20"
		)
		(pin "C21"
		)
		(pin "C22"
		)
		(pin "D16"
		)
		(pin "D17"
		)
		(pin "D18"
		)
		(pin "D19"
		)
		(pin "D21"
		)
		(pin "D22"
		)
		(pin "E18"
		)
		(pin "E19"
		)
		(pin "E20"
		)
		(pin "E21"
		)
		(pin "F17"
		)
		(pin "F18"
		)
		(pin "F20"
		)
		(pin "F21"
		)
		(pin "F22"
		)
		(pin "G17"
		)
		(pin "G18"
		)
		(pin "G19"
		)
		(pin "G20"
		)
		(pin "G22"
		)
		(pin "H17"
		)
		(pin "H19"
		)
		(pin "H20"
		)
		(pin "H21"
		)
		(pin "H22"
		)
		(pin "J17"
		)
		(pin "J18"
		)
		(pin "J19"
		)
		(pin "K18"
		)
		(pin "K19"
		)
		(pin "K20"
		)
		(pin "L17"
		)
		(pin "L18"
		)
		(pin "AA15"
		)
		(pin "AA16"
		)
		(pin "AA17"
		)
		(pin "AA18"
		)
		(pin "AB14"
		)
		(pin "AB15"
		)
		(pin "AB17"
		)
		(pin "AB18"
		)
		(pin "AB19"
		)
		(pin "AC14"
		)
		(pin "AC15"
		)
		(pin "AC16"
		)
		(pin "AC17"
		)
		(pin "AC19"
		)
		(pin "AD14"
		)
		(pin "AD16"
		)
		(pin "AD17"
		)
		(pin "AD18"
		)
		(pin "AD19"
		)
		(pin "AE14"
		)
		(pin "AE15"
		)
		(pin "AE16"
		)
		(pin "AE18"
		)
		(pin "AE19"
		)
		(pin "AF15"
		)
		(pin "AF16"
		)
		(pin "AF17"
		)
		(pin "AF18"
		)
		(pin "AG14"
		)
		(pin "AG15"
		)
		(pin "AG17"
		)
		(pin "AG18"
		)
		(pin "AG19"
		)
		(pin "AH15"
		)
		(pin "AH16"
		)
		(pin "AH17"
		)
		(pin "AH19"
		)
		(pin "AJ16"
		)
		(pin "AJ17"
		)
		(pin "AJ18"
		)
		(pin "AJ19"
		)
		(pin "AK15"
		)
		(pin "AK16"
		)
		(pin "AK18"
		)
		(pin "AK19"
		)
		(pin "Y14"
		)
		(pin "Y15"
		)
		(pin "Y16"
		)
		(pin "Y18"
		)
		(pin "Y19"
		)
		(pin "AB7"
		)
		(pin "AC1"
		)
		(pin "AC2"
		)
		(pin "AC4"
		)
		(pin "AC5"
		)
		(pin "AC6"
		)
		(pin "AC7"
		)
		(pin "AD1"
		)
		(pin "AD2"
		)
		(pin "AD3"
		)
		(pin "AD4"
		)
		(pin "AD6"
		)
		(pin "AD7"
		)
		(pin "AE1"
		)
		(pin "AE3"
		)
		(pin "AE4"
		)
		(pin "AE5"
		)
		(pin "AE6"
		)
		(pin "AF1"
		)
		(pin "AF2"
		)
		(pin "AF3"
		)
		(pin "AF5"
		)
		(pin "AF6"
		)
		(pin "AF7"
		)
		(pin "AF8"
		)
		(pin "AG2"
		)
		(pin "AG3"
		)
		(pin "AG4"
		)
		(pin "AG5"
		)
		(pin "AG7"
		)
		(pin "AG8"
		)
		(pin "AH1"
		)
		(pin "AH2"
		)
		(pin "AH4"
		)
		(pin "AH5"
		)
		(pin "AH6"
		)
		(pin "AH7"
		)
		(pin "AJ1"
		)
		(pin "AJ2"
		)
		(pin "AJ3"
		)
		(pin "AJ4"
		)
		(pin "AJ6"
		)
		(pin "AJ7"
		)
		(pin "AJ8"
		)
		(pin "AK1"
		)
		(pin "AK3"
		)
		(pin "AK4"
		)
		(pin "AK5"
		)
		(pin "AK6"
		)
		(pin "AK8"
		)
		(pin "AA20"
		)
		(pin "AA21"
		)
		(pin "E28"
		)
		(pin "E29"
		)
		(instances
			(project "k410t-devboard"
				(path ""
					(reference "U1")
					(unit 5)
				)
			)
		)
	)
	(symbol
		(lib_id "antmicroCapacitors0402:C_100n_0402")
		(at 142.24 52.07 270)
		(mirror x)
		(unit 1)
		(exclude_from_sim no)
		(in_bom yes)
		(on_board yes)
		(dnp no)
		(property "Reference" "C101"
			(at 141.605 47.625 90)
			(effects
				(font
					(size 1.27 1.27)
				)
				(justify right)
			)
		)
		(property "Value" "C_100n_0402"
			(at 132.08 31.75 0)
			(effects
				(font
					(size 1.27 1.27)
					(thickness 0.15)
				)
				(justify left bottom)
				(hide yes)
			)
		)
		(property "Footprint" "antmicro-footprints:C_0402_1005Metric"
			(at 129.54 31.75 0)
			(effects
				(font
					(size 1.27 1.27)
					(thickness 0.15)
				)
				(justify left bottom)
				(hide yes)
			)
		)
		(property "Datasheet" "https://www.murata.com/products/productdetail?partno=GRM155R61H104KE14%23"
			(at 127 31.75 0)
			(effects
				(font
					(size 1.27 1.27)
					(thickness 0.15)
				)
				(justify left bottom)
				(hide yes)
			)
		)
		(property "Description" ""
			(at 142.24 52.07 0)
			(effects
				(font
					(size 1.27 1.27)
				)
			)
		)
		(property "Manufacturer" "Murata"
			(at 121.92 31.75 0)
			(effects
				(font
					(size 1.27 1.27)
					(thickness 0.15)
				)
				(justify left bottom)
				(hide yes)
			)
		)
		(property "MPN" "GRM155R61H104KE14D"
			(at 124.46 31.75 0)
			(effects
				(font
					(size 1.27 1.27)
					(thickness 0.15)
				)
				(justify left bottom)
				(hide yes)
			)
		)
		(property "Val" "100n"
			(at 141.605 51.435 90)
			(effects
				(font
					(size 1.27 1.27)
					(thickness 0.15)
				)
				(justify right)
			)
		)
		(property "License" "Apache-2.0"
			(at 119.38 31.75 0)
			(effects
				(font
					(size 1.27 1.27)
					(thickness 0.15)
				)
				(justify left bottom)
				(hide yes)
			)
		)
		(property "Author" "Antmicro"
			(at 116.84 31.75 0)
			(effects
				(font
					(size 1.27 1.27)
					(thickness 0.15)
				)
				(justify left bottom)
				(hide yes)
			)
		)
		(property "Voltage" "50V"
			(at 114.3 31.75 0)
			(effects
				(font
					(size 1.27 1.27)
				)
				(justify left bottom)
				(hide yes)
			)
		)
		(property "Dielectric" "X5R"
			(at 111.76 31.75 0)
			(effects
				(font
					(size 1.27 1.27)
				)
				(justify left bottom)
				(hide yes)
			)
		)
		(pin "1"
		)
		(pin "2"
		)
		(instances
			(project "k410t-devboard"
				(path ""
					(reference "C101")
					(unit 1)
				)
			)
		)
	)
	(symbol
		(lib_id "antmicroCapacitors0402:C_100n_0402")
		(at 165.1 52.07 270)
		(mirror x)
		(unit 1)
		(exclude_from_sim no)
		(in_bom yes)
		(on_board yes)
		(dnp no)
		(property "Reference" "C84"
			(at 164.465 47.625 90)
			(effects
				(font
					(size 1.27 1.27)
				)
				(justify right)
			)
		)
		(property "Value" "C_100n_0402"
			(at 154.94 31.75 0)
			(effects
				(font
					(size 1.27 1.27)
					(thickness 0.15)
				)
				(justify left bottom)
				(hide yes)
			)
		)
		(property "Footprint" "antmicro-footprints:C_0402_1005Metric"
			(at 152.4 31.75 0)
			(effects
				(font
					(size 1.27 1.27)
					(thickness 0.15)
				)
				(justify left bottom)
				(hide yes)
			)
		)
		(property "Datasheet" "https://www.murata.com/products/productdetail?partno=GRM155R61H104KE14%23"
			(at 149.86 31.75 0)
			(effects
				(font
					(size 1.27 1.27)
					(thickness 0.15)
				)
				(justify left bottom)
				(hide yes)
			)
		)
		(property "Description" ""
			(at 165.1 52.07 0)
			(effects
				(font
					(size 1.27 1.27)
				)
			)
		)
		(property "Manufacturer" "Murata"
			(at 144.78 31.75 0)
			(effects
				(font
					(size 1.27 1.27)
					(thickness 0.15)
				)
				(justify left bottom)
				(hide yes)
			)
		)
		(property "MPN" "GRM155R61H104KE14D"
			(at 147.32 31.75 0)
			(effects
				(font
					(size 1.27 1.27)
					(thickness 0.15)
				)
				(justify left bottom)
				(hide yes)
			)
		)
		(property "Val" "100n"
			(at 164.465 51.435 90)
			(effects
				(font
					(size 1.27 1.27)
					(thickness 0.15)
				)
				(justify right)
			)
		)
		(property "License" "Apache-2.0"
			(at 142.24 31.75 0)
			(effects
				(font
					(size 1.27 1.27)
					(thickness 0.15)
				)
				(justify left bottom)
				(hide yes)
			)
		)
		(property "Author" "Antmicro"
			(at 139.7 31.75 0)
			(effects
				(font
					(size 1.27 1.27)
					(thickness 0.15)
				)
				(justify left bottom)
				(hide yes)
			)
		)
		(property "Voltage" "50V"
			(at 137.16 31.75 0)
			(effects
				(font
					(size 1.27 1.27)
				)
				(justify left bottom)
				(hide yes)
			)
		)
		(property "Dielectric" "X5R"
			(at 134.62 31.75 0)
			(effects
				(font
					(size 1.27 1.27)
				)
				(justify left bottom)
				(hide yes)
			)
		)
		(pin "1"
		)
		(pin "2"
		)
		(instances
			(project "k410t-devboard"
				(path ""
					(reference "C84")
					(unit 1)
				)
			)
		)
	)
	(symbol
		(lib_id "antmicroCapacitors0402:C_100n_0402")
		(at 255.27 52.07 90)
		(unit 1)
		(exclude_from_sim no)
		(in_bom yes)
		(on_board yes)
		(dnp no)
		(property "Reference" "C71"
			(at 255.905 47.625 90)
			(effects
				(font
					(size 1.27 1.27)
				)
				(justify right)
			)
		)
		(property "Value" "C_100n_0402"
			(at 265.43 31.75 0)
			(effects
				(font
					(size 1.27 1.27)
					(thickness 0.15)
				)
				(justify left bottom)
				(hide yes)
			)
		)
		(property "Footprint" "antmicro-footprints:C_0402_1005Metric"
			(at 267.97 31.75 0)
			(effects
				(font
					(size 1.27 1.27)
					(thickness 0.15)
				)
				(justify left bottom)
				(hide yes)
			)
		)
		(property "Datasheet" "https://www.murata.com/products/productdetail?partno=GRM155R61H104KE14%23"
			(at 270.51 31.75 0)
			(effects
				(font
					(size 1.27 1.27)
					(thickness 0.15)
				)
				(justify left bottom)
				(hide yes)
			)
		)
		(property "Description" ""
			(at 255.27 52.07 0)
			(effects
				(font
					(size 1.27 1.27)
				)
			)
		)
		(property "Manufacturer" "Murata"
			(at 275.59 31.75 0)
			(effects
				(font
					(size 1.27 1.27)
					(thickness 0.15)
				)
				(justify left bottom)
				(hide yes)
			)
		)
		(property "MPN" "GRM155R61H104KE14D"
			(at 273.05 31.75 0)
			(effects
				(font
					(size 1.27 1.27)
					(thickness 0.15)
				)
				(justify left bottom)
				(hide yes)
			)
		)
		(property "Val" "100n"
			(at 255.905 51.435 90)
			(effects
				(font
					(size 1.27 1.27)
					(thickness 0.15)
				)
				(justify right)
			)
		)
		(property "License" "Apache-2.0"
			(at 278.13 31.75 0)
			(effects
				(font
					(size 1.27 1.27)
					(thickness 0.15)
				)
				(justify left bottom)
				(hide yes)
			)
		)
		(property "Author" "Antmicro"
			(at 280.67 31.75 0)
			(effects
				(font
					(size 1.27 1.27)
					(thickness 0.15)
				)
				(justify left bottom)
				(hide yes)
			)
		)
		(property "Voltage" "50V"
			(at 283.21 31.75 0)
			(effects
				(font
					(size 1.27 1.27)
				)
				(justify left bottom)
				(hide yes)
			)
		)
		(property "Dielectric" "X5R"
			(at 285.75 31.75 0)
			(effects
				(font
					(size 1.27 1.27)
				)
				(justify left bottom)
				(hide yes)
			)
		)
		(pin "1"
		)
		(pin "2"
		)
		(instances
			(project "k410t-devboard"
				(path ""
					(reference "C71")
					(unit 1)
				)
			)
		)
	)
	(symbol
		(lib_id "antmicropower:+1V8")
		(at 129.54 41.91 0)
		(mirror y)
		(unit 1)
		(exclude_from_sim no)
		(in_bom yes)
		(on_board yes)
		(dnp no)
		(fields_autoplaced yes)
		(property "Reference" "#PWR039"
			(at 129.54 45.72 0)
			(effects
				(font
					(size 1.27 1.27)
				)
				(hide yes)
			)
		)
		(property "Value" "+1V8"
			(at 129.54 38.354 0)
			(effects
				(font
					(size 1.27 1.27)
				)
			)
		)
		(property "Footprint" ""
			(at 114.3 49.53 0)
			(effects
				(font
					(size 1.27 1.27)
					(thickness 0.15)
				)
				(justify left bottom)
				(hide yes)
			)
		)
		(property "Datasheet" ""
			(at 114.3 52.07 0)
			(effects
				(font
					(size 1.27 1.27)
					(thickness 0.15)
				)
				(justify left bottom)
				(hide yes)
			)
		)
		(property "Description" ""
			(at 129.54 41.91 0)
			(effects
				(font
					(size 1.27 1.27)
				)
			)
		)
		(property "Author" "Antmicro"
			(at 114.3 49.53 0)
			(effects
				(font
					(size 1.27 1.27)
					(thickness 0.15)
				)
				(justify left bottom)
				(hide yes)
			)
		)
		(property "License" "Apache-2.0"
			(at 114.3 52.07 0)
			(effects
				(font
					(size 1.27 1.27)
					(thickness 0.15)
				)
				(justify left bottom)
				(hide yes)
			)
		)
		(pin "1"
		)
		(instances
			(project "k410t-devboard"
				(path ""
					(reference "#PWR039")
					(unit 1)
				)
			)
		)
	)
	(symbol
		(lib_id "antmicropower:+0V675_VREF")
		(at 270.51 107.95 0)
		(unit 1)
		(exclude_from_sim no)
		(in_bom yes)
		(on_board yes)
		(dnp no)
		(property "Reference" "#PWR033"
			(at 270.51 111.76 0)
			(effects
				(font
					(size 1.27 1.27)
				)
				(hide yes)
			)
		)
		(property "Value" "+0V675_VREF"
			(at 270.51 104.394 0)
			(effects
				(font
					(size 1.27 1.27)
				)
			)
		)
		(property "Footprint" ""
			(at 270.51 107.95 0)
			(effects
				(font
					(size 1.27 1.27)
				)
				(hide yes)
			)
		)
		(property "Datasheet" ""
			(at 270.51 107.95 0)
			(effects
				(font
					(size 1.27 1.27)
				)
				(hide yes)
			)
		)
		(property "Description" ""
			(at 270.51 107.95 0)
			(effects
				(font
					(size 1.27 1.27)
				)
			)
		)
		(pin "1"
		)
		(instances
			(project "k410t-devboard"
				(path ""
					(reference "#PWR033")
					(unit 1)
				)
			)
		)
	)
	(symbol
		(lib_id "antmicropower:GND")
		(at 134.62 55.88 0)
		(unit 1)
		(exclude_from_sim no)
		(in_bom yes)
		(on_board yes)
		(dnp no)
		(property "Reference" "#PWR029"
			(at 134.62 62.23 0)
			(effects
				(font
					(size 1.27 1.27)
				)
				(hide yes)
			)
		)
		(property "Value" "GND"
			(at 134.62 59.69 0)
			(effects
				(font
					(size 1.27 1.27)
				)
			)
		)
		(property "Footprint" ""
			(at 143.51 63.5 0)
			(effects
				(font
					(size 1.27 1.27)
					(thickness 0.15)
				)
				(justify left bottom)
				(hide yes)
			)
		)
		(property "Datasheet" ""
			(at 143.51 68.58 0)
			(effects
				(font
					(size 1.27 1.27)
					(thickness 0.15)
				)
				(justify left bottom)
				(hide yes)
			)
		)
		(property "Description" ""
			(at 134.62 55.88 0)
			(effects
				(font
					(size 1.27 1.27)
				)
			)
		)
		(property "Author" "Antmicro"
			(at 143.51 63.5 0)
			(effects
				(font
					(size 1.27 1.27)
					(thickness 0.15)
				)
				(justify left bottom)
				(hide yes)
			)
		)
		(property "License" "Apache-2.0"
			(at 143.51 66.04 0)
			(effects
				(font
					(size 1.27 1.27)
					(thickness 0.15)
				)
				(justify left bottom)
				(hide yes)
			)
		)
		(pin "1"
		)
		(instances
			(project "k410t-devboard"
				(path ""
					(reference "#PWR029")
					(unit 1)
				)
			)
		)
	)
	(symbol
		(lib_id "antmicropower:GND")
		(at 255.27 71.12 0)
		(unit 1)
		(exclude_from_sim no)
		(in_bom yes)
		(on_board yes)
		(dnp no)
		(property "Reference" "#PWR031"
			(at 255.27 77.47 0)
			(effects
				(font
					(size 1.27 1.27)
				)
				(hide yes)
			)
		)
		(property "Value" "GND"
			(at 255.27 74.93 0)
			(effects
				(font
					(size 1.27 1.27)
				)
			)
		)
		(property "Footprint" ""
			(at 264.16 78.74 0)
			(effects
				(font
					(size 1.27 1.27)
					(thickness 0.15)
				)
				(justify left bottom)
				(hide yes)
			)
		)
		(property "Datasheet" ""
			(at 264.16 83.82 0)
			(effects
				(font
					(size 1.27 1.27)
					(thickness 0.15)
				)
				(justify left bottom)
				(hide yes)
			)
		)
		(property "Description" ""
			(at 255.27 71.12 0)
			(effects
				(font
					(size 1.27 1.27)
				)
			)
		)
		(property "Author" "Antmicro"
			(at 264.16 78.74 0)
			(effects
				(font
					(size 1.27 1.27)
					(thickness 0.15)
				)
				(justify left bottom)
				(hide yes)
			)
		)
		(property "License" "Apache-2.0"
			(at 264.16 81.28 0)
			(effects
				(font
					(size 1.27 1.27)
					(thickness 0.15)
				)
				(justify left bottom)
				(hide yes)
			)
		)
		(pin "1"
		)
		(instances
			(project "k410t-devboard"
				(path ""
					(reference "#PWR031")
					(unit 1)
				)
			)
		)
	)
	(symbol
		(lib_id "antmicropower:+0V675_VREF")
		(at 270.51 173.99 0)
		(unit 1)
		(exclude_from_sim no)
		(in_bom yes)
		(on_board yes)
		(dnp no)
		(property "Reference" "#PWR037"
			(at 270.51 177.8 0)
			(effects
				(font
					(size 1.27 1.27)
				)
				(hide yes)
			)
		)
		(property "Value" "+0V675_VREF"
			(at 270.51 170.434 0)
			(effects
				(font
					(size 1.27 1.27)
				)
			)
		)
		(property "Footprint" ""
			(at 270.51 173.99 0)
			(effects
				(font
					(size 1.27 1.27)
				)
				(hide yes)
			)
		)
		(property "Datasheet" ""
			(at 270.51 173.99 0)
			(effects
				(font
					(size 1.27 1.27)
				)
				(hide yes)
			)
		)
		(property "Description" ""
			(at 270.51 173.99 0)
			(effects
				(font
					(size 1.27 1.27)
				)
			)
		)
		(pin "1"
		)
		(instances
			(project "k410t-devboard"
				(path ""
					(reference "#PWR037")
					(unit 1)
				)
			)
		)
	)
	(symbol
		(lib_id "antmicropower:GND")
		(at 270.51 118.11 0)
		(unit 1)
		(exclude_from_sim no)
		(in_bom yes)
		(on_board yes)
		(dnp no)
		(property "Reference" "#PWR036"
			(at 270.51 124.46 0)
			(effects
				(font
					(size 1.27 1.27)
				)
				(hide yes)
			)
		)
		(property "Value" "GND"
			(at 270.51 121.92 0)
			(effects
				(font
					(size 1.27 1.27)
				)
			)
		)
		(property "Footprint" ""
			(at 279.4 125.73 0)
			(effects
				(font
					(size 1.27 1.27)
					(thickness 0.15)
				)
				(justify left bottom)
				(hide yes)
			)
		)
		(property "Datasheet" ""
			(at 279.4 130.81 0)
			(effects
				(font
					(size 1.27 1.27)
					(thickness 0.15)
				)
				(justify left bottom)
				(hide yes)
			)
		)
		(property "Description" ""
			(at 270.51 118.11 0)
			(effects
				(font
					(size 1.27 1.27)
				)
			)
		)
		(property "Author" "Antmicro"
			(at 279.4 125.73 0)
			(effects
				(font
					(size 1.27 1.27)
					(thickness 0.15)
				)
				(justify left bottom)
				(hide yes)
			)
		)
		(property "License" "Apache-2.0"
			(at 279.4 128.27 0)
			(effects
				(font
					(size 1.27 1.27)
					(thickness 0.15)
				)
				(justify left bottom)
				(hide yes)
			)
		)
		(pin "1"
		)
		(instances
			(project "k410t-devboard"
				(path ""
					(reference "#PWR036")
					(unit 1)
				)
			)
		)
	)
	(symbol
		(lib_id "antmicropower:GND")
		(at 270.51 184.15 0)
		(unit 1)
		(exclude_from_sim no)
		(in_bom yes)
		(on_board yes)
		(dnp no)
		(property "Reference" "#PWR038"
			(at 270.51 190.5 0)
			(effects
				(font
					(size 1.27 1.27)
				)
				(hide yes)
			)
		)
		(property "Value" "GND"
			(at 270.51 187.96 0)
			(effects
				(font
					(size 1.27 1.27)
				)
			)
		)
		(property "Footprint" ""
			(at 279.4 191.77 0)
			(effects
				(font
					(size 1.27 1.27)
					(thickness 0.15)
				)
				(justify left bottom)
				(hide yes)
			)
		)
		(property "Datasheet" ""
			(at 279.4 196.85 0)
			(effects
				(font
					(size 1.27 1.27)
					(thickness 0.15)
				)
				(justify left bottom)
				(hide yes)
			)
		)
		(property "Description" ""
			(at 270.51 184.15 0)
			(effects
				(font
					(size 1.27 1.27)
				)
			)
		)
		(property "Author" "Antmicro"
			(at 279.4 191.77 0)
			(effects
				(font
					(size 1.27 1.27)
					(thickness 0.15)
				)
				(justify left bottom)
				(hide yes)
			)
		)
		(property "License" "Apache-2.0"
			(at 279.4 194.31 0)
			(effects
				(font
					(size 1.27 1.27)
					(thickness 0.15)
				)
				(justify left bottom)
				(hide yes)
			)
		)
		(pin "1"
		)
		(instances
			(project "k410t-devboard"
				(path ""
					(reference "#PWR038")
					(unit 1)
				)
			)
		)
	)
	(symbol
		(lib_id "antmicroCapacitors0402:C_100n_0402")
		(at 180.34 52.07 270)
		(mirror x)
		(unit 1)
		(exclude_from_sim no)
		(in_bom yes)
		(on_board yes)
		(dnp no)
		(property "Reference" "C70"
			(at 179.705 47.625 90)
			(effects
				(font
					(size 1.27 1.27)
				)
				(justify right)
			)
		)
		(property "Value" "C_100n_0402"
			(at 170.18 31.75 0)
			(effects
				(font
					(size 1.27 1.27)
					(thickness 0.15)
				)
				(justify left bottom)
				(hide yes)
			)
		)
		(property "Footprint" "antmicro-footprints:C_0402_1005Metric"
			(at 167.64 31.75 0)
			(effects
				(font
					(size 1.27 1.27)
					(thickness 0.15)
				)
				(justify left bottom)
				(hide yes)
			)
		)
		(property "Datasheet" "https://www.murata.com/products/productdetail?partno=GRM155R61H104KE14%23"
			(at 165.1 31.75 0)
			(effects
				(font
					(size 1.27 1.27)
					(thickness 0.15)
				)
				(justify left bottom)
				(hide yes)
			)
		)
		(property "Description" ""
			(at 180.34 52.07 0)
			(effects
				(font
					(size 1.27 1.27)
				)
			)
		)
		(property "Manufacturer" "Murata"
			(at 160.02 31.75 0)
			(effects
				(font
					(size 1.27 1.27)
					(thickness 0.15)
				)
				(justify left bottom)
				(hide yes)
			)
		)
		(property "MPN" "GRM155R61H104KE14D"
			(at 162.56 31.75 0)
			(effects
				(font
					(size 1.27 1.27)
					(thickness 0.15)
				)
				(justify left bottom)
				(hide yes)
			)
		)
		(property "Val" "100n"
			(at 179.705 51.435 90)
			(effects
				(font
					(size 1.27 1.27)
					(thickness 0.15)
				)
				(justify right)
			)
		)
		(property "License" "Apache-2.0"
			(at 157.48 31.75 0)
			(effects
				(font
					(size 1.27 1.27)
					(thickness 0.15)
				)
				(justify left bottom)
				(hide yes)
			)
		)
		(property "Author" "Antmicro"
			(at 154.94 31.75 0)
			(effects
				(font
					(size 1.27 1.27)
					(thickness 0.15)
				)
				(justify left bottom)
				(hide yes)
			)
		)
		(property "Voltage" "50V"
			(at 152.4 31.75 0)
			(effects
				(font
					(size 1.27 1.27)
				)
				(justify left bottom)
				(hide yes)
			)
		)
		(property "Dielectric" "X5R"
			(at 149.86 31.75 0)
			(effects
				(font
					(size 1.27 1.27)
				)
				(justify left bottom)
				(hide yes)
			)
		)
		(pin "1"
		)
		(pin "2"
		)
		(instances
			(project "k410t-devboard"
				(path ""
					(reference "C70")
					(unit 1)
				)
			)
		)
	)
	(symbol
		(lib_id "antmicroCapacitors0603:C_47u_0603")
		(at 300.99 46.99 90)
		(mirror x)
		(unit 1)
		(exclude_from_sim no)
		(in_bom yes)
		(on_board yes)
		(dnp no)
		(property "Reference" "C109"
			(at 301.625 47.6377 90)
			(effects
				(font
					(size 1.27 1.27)
				)
				(justify right)
			)
		)
		(property "Value" "C_47u_0603"
			(at 311.15 67.31 0)
			(effects
				(font
					(size 1.27 1.27)
					(thickness 0.15)
				)
				(justify left bottom)
				(hide yes)
			)
		)
		(property "Footprint" "antmicro-footprints:C_0603_1608Metric"
			(at 313.69 67.31 0)
			(effects
				(font
					(size 1.27 1.27)
					(thickness 0.15)
				)
				(justify left bottom)
				(hide yes)
			)
		)
		(property "Datasheet" "https://www.murata.com/products/productdetail?partno=GRM188R60J476ME15%23"
			(at 316.23 67.31 0)
			(effects
				(font
					(size 1.27 1.27)
					(thickness 0.15)
				)
				(justify left bottom)
				(hide yes)
			)
		)
		(property "Description" ""
			(at 300.99 46.99 0)
			(effects
				(font
					(size 1.27 1.27)
				)
			)
		)
		(property "Manufacturer" "Murata"
			(at 321.31 67.31 0)
			(effects
				(font
					(size 1.27 1.27)
					(thickness 0.15)
				)
				(justify left bottom)
				(hide yes)
			)
		)
		(property "MPN" "GRM188R60J476ME15D"
			(at 318.77 67.31 0)
			(effects
				(font
					(size 1.27 1.27)
					(thickness 0.15)
				)
				(justify left bottom)
				(hide yes)
			)
		)
		(property "Val" "47u"
			(at 301.625 51.4477 90)
			(effects
				(font
					(size 1.27 1.27)
					(thickness 0.15)
				)
				(justify right)
			)
		)
		(property "License" "Apache-2.0"
			(at 323.85 67.31 0)
			(effects
				(font
					(size 1.27 1.27)
					(thickness 0.15)
				)
				(justify left bottom)
				(hide yes)
			)
		)
		(property "Author" "Antmicro"
			(at 326.39 67.31 0)
			(effects
				(font
					(size 1.27 1.27)
					(thickness 0.15)
				)
				(justify left bottom)
				(hide yes)
			)
		)
		(property "Voltage" ""
			(at 328.93 67.31 0)
			(effects
				(font
					(size 1.27 1.27)
				)
				(justify left bottom)
				(hide yes)
			)
		)
		(property "Dielectric" ""
			(at 331.47 67.31 0)
			(effects
				(font
					(size 1.27 1.27)
				)
				(justify left bottom)
				(hide yes)
			)
		)
		(pin "1"
		)
		(pin "2"
		)
		(instances
			(project "k410t-devboard"
				(path ""
					(reference "C109")
					(unit 1)
				)
			)
		)
	)
	(symbol
		(lib_id "antmicroCapacitors0402:C_100n_0402")
		(at 270.51 52.07 90)
		(unit 1)
		(exclude_from_sim no)
		(in_bom yes)
		(on_board yes)
		(dnp no)
		(property "Reference" "C85"
			(at 271.145 47.625 90)
			(effects
				(font
					(size 1.27 1.27)
				)
				(justify right)
			)
		)
		(property "Value" "C_100n_0402"
			(at 280.67 31.75 0)
			(effects
				(font
					(size 1.27 1.27)
					(thickness 0.15)
				)
				(justify left bottom)
				(hide yes)
			)
		)
		(property "Footprint" "antmicro-footprints:C_0402_1005Metric"
			(at 283.21 31.75 0)
			(effects
				(font
					(size 1.27 1.27)
					(thickness 0.15)
				)
				(justify left bottom)
				(hide yes)
			)
		)
		(property "Datasheet" "https://www.murata.com/products/productdetail?partno=GRM155R61H104KE14%23"
			(at 285.75 31.75 0)
			(effects
				(font
					(size 1.27 1.27)
					(thickness 0.15)
				)
				(justify left bottom)
				(hide yes)
			)
		)
		(property "Description" ""
			(at 270.51 52.07 0)
			(effects
				(font
					(size 1.27 1.27)
				)
			)
		)
		(property "Manufacturer" "Murata"
			(at 290.83 31.75 0)
			(effects
				(font
					(size 1.27 1.27)
					(thickness 0.15)
				)
				(justify left bottom)
				(hide yes)
			)
		)
		(property "MPN" "GRM155R61H104KE14D"
			(at 288.29 31.75 0)
			(effects
				(font
					(size 1.27 1.27)
					(thickness 0.15)
				)
				(justify left bottom)
				(hide yes)
			)
		)
		(property "Val" "100n"
			(at 271.145 51.435 90)
			(effects
				(font
					(size 1.27 1.27)
					(thickness 0.15)
				)
				(justify right)
			)
		)
		(property "License" "Apache-2.0"
			(at 293.37 31.75 0)
			(effects
				(font
					(size 1.27 1.27)
					(thickness 0.15)
				)
				(justify left bottom)
				(hide yes)
			)
		)
		(property "Author" "Antmicro"
			(at 295.91 31.75 0)
			(effects
				(font
					(size 1.27 1.27)
					(thickness 0.15)
				)
				(justify left bottom)
				(hide yes)
			)
		)
		(property "Voltage" "50V"
			(at 298.45 31.75 0)
			(effects
				(font
					(size 1.27 1.27)
				)
				(justify left bottom)
				(hide yes)
			)
		)
		(property "Dielectric" "X5R"
			(at 300.99 31.75 0)
			(effects
				(font
					(size 1.27 1.27)
				)
				(justify left bottom)
				(hide yes)
			)
		)
		(pin "1"
		)
		(pin "2"
		)
		(instances
			(project "k410t-devboard"
				(path ""
					(reference "C85")
					(unit 1)
				)
			)
		)
	)
	(symbol
		(lib_id "antmicropower:+1V35")
		(at 304.8 41.91 0)
		(unit 1)
		(exclude_from_sim no)
		(in_bom yes)
		(on_board yes)
		(dnp no)
		(fields_autoplaced yes)
		(property "Reference" "#PWR040"
			(at 304.8 45.72 0)
			(effects
				(font
					(size 1.27 1.27)
				)
				(hide yes)
			)
		)
		(property "Value" "+1V35"
			(at 304.8 38.354 0)
			(effects
				(font
					(size 1.27 1.27)
				)
			)
		)
		(property "Footprint" ""
			(at 304.8 41.91 0)
			(effects
				(font
					(size 1.27 1.27)
				)
				(hide yes)
			)
		)
		(property "Datasheet" ""
			(at 304.8 41.91 0)
			(effects
				(font
					(size 1.27 1.27)
				)
				(hide yes)
			)
		)
		(property "Description" ""
			(at 304.8 41.91 0)
			(effects
				(font
					(size 1.27 1.27)
				)
			)
		)
		(pin "1"
		)
		(instances
			(project "k410t-devboard"
				(path ""
					(reference "#PWR040")
					(unit 1)
				)
			)
		)
	)
	(symbol
		(lib_id "antmicroCapacitors0402:C_100n_0402")
		(at 172.72 52.07 270)
		(mirror x)
		(unit 1)
		(exclude_from_sim no)
		(in_bom yes)
		(on_board yes)
		(dnp no)
		(property "Reference" "C78"
			(at 172.085 47.625 90)
			(effects
				(font
					(size 1.27 1.27)
				)
				(justify right)
			)
		)
		(property "Value" "C_100n_0402"
			(at 162.56 31.75 0)
			(effects
				(font
					(size 1.27 1.27)
					(thickness 0.15)
				)
				(justify left bottom)
				(hide yes)
			)
		)
		(property "Footprint" "antmicro-footprints:C_0402_1005Metric"
			(at 160.02 31.75 0)
			(effects
				(font
					(size 1.27 1.27)
					(thickness 0.15)
				)
				(justify left bottom)
				(hide yes)
			)
		)
		(property "Datasheet" "https://www.murata.com/products/productdetail?partno=GRM155R61H104KE14%23"
			(at 157.48 31.75 0)
			(effects
				(font
					(size 1.27 1.27)
					(thickness 0.15)
				)
				(justify left bottom)
				(hide yes)
			)
		)
		(property "Description" ""
			(at 172.72 52.07 0)
			(effects
				(font
					(size 1.27 1.27)
				)
			)
		)
		(property "Manufacturer" "Murata"
			(at 152.4 31.75 0)
			(effects
				(font
					(size 1.27 1.27)
					(thickness 0.15)
				)
				(justify left bottom)
				(hide yes)
			)
		)
		(property "MPN" "GRM155R61H104KE14D"
			(at 154.94 31.75 0)
			(effects
				(font
					(size 1.27 1.27)
					(thickness 0.15)
				)
				(justify left bottom)
				(hide yes)
			)
		)
		(property "Val" "100n"
			(at 172.085 51.435 90)
			(effects
				(font
					(size 1.27 1.27)
					(thickness 0.15)
				)
				(justify right)
			)
		)
		(property "License" "Apache-2.0"
			(at 149.86 31.75 0)
			(effects
				(font
					(size 1.27 1.27)
					(thickness 0.15)
				)
				(justify left bottom)
				(hide yes)
			)
		)
		(property "Author" "Antmicro"
			(at 147.32 31.75 0)
			(effects
				(font
					(size 1.27 1.27)
					(thickness 0.15)
				)
				(justify left bottom)
				(hide yes)
			)
		)
		(property "Voltage" "50V"
			(at 144.78 31.75 0)
			(effects
				(font
					(size 1.27 1.27)
				)
				(justify left bottom)
				(hide yes)
			)
		)
		(property "Dielectric" "X5R"
			(at 142.24 31.75 0)
			(effects
				(font
					(size 1.27 1.27)
				)
				(justify left bottom)
				(hide yes)
			)
		)
		(pin "1"
		)
		(pin "2"
		)
		(instances
			(project "k410t-devboard"
				(path ""
					(reference "C78")
					(unit 1)
				)
			)
		)
	)
)
